G04 ================== begin FILE IDENTIFICATION RECORD ==================*
G04 Layout Name:  9054_F0T_PDB_BD_GPU_F_V04_1213_1550.brd*
G04 Film Name:    pmt*
G04 File Format:  Gerber RS274X*
G04 File Origin:  Cadence Allegro 17.2-S081*
G04 Origin Date:  Wed Dec 28 10:19:02 2022*
G04 *
G04 Layer:  DRAWING FORMAT/TITLE_BLOCK_A*
G04 Layer:  VIA CLASS/PASTEMASK_TOP*
G04 Layer:  PIN/PASTEMASK_TOP*
G04 Layer:  PACKAGE GEOMETRY/PASTEMASK_TOP*
G04 Layer:  MANUFACTURING/PHOTOPLOT_OUTLINE*
G04 Layer:  DRAWING FORMAT/TITLE_BLOCK*
G04 Layer:  DRAWING FORMAT/TITLE_DATA_PMT*
G04 *
G04 Offset:    (0.00 0.00)*
G04 Mirror:    No*
G04 Mode:      Positive*
G04 Rotation:  0*
G04 FullContactRelief:  No*
G04 UndefLineWidth:     6.00*
G04 ================== end FILE IDENTIFICATION RECORD ====================*
%FSLAX25Y25*MOIN*%
%IR0*IPPOS*OFA0.00000B0.00000*MIA0B0*SFA1.00000B1.00000*%
%AMMACRO70*
4,1,32,-.01575,.06201,
-.01575,.0502,
.00197,.0502,
.00197,.04035,
-.01575,.04035,
-.01575,.03248,
.00197,.03248,
.00197,.02461,
-.01575,.02461,
-.01575,.01673,
.00197,.01673,
.00197,.00886,
-.01575,.00886,
-.01575,.00098,
.00197,.00098,
.00197,-.00689,
-.01575,-.00689,
-.01575,-.01476,
.00197,-.01476,
.00197,-.02264,
-.01575,-.02264,
-.01575,-.03051,
.00197,-.03051,
.00197,-.03839,
-.01575,-.03839,
-.01575,-.04626,
.00197,-.04626,
.00197,-.05413,
-.01575,-.05413,
-.01575,-.06201,
.01575,-.06201,
.01575,.06201,
-.01575,.06201,
0.0*
%
%ADD70MACRO70*%
%ADD71R,.032X.007*%
%ADD12C,.03*%
%ADD73C,.061*%
%ADD64R,.063X.119*%
%ADD63R,.138X.063*%
%ADD17C,.07*%
%ADD26R,.13X.099*%
%ADD19R,.063X.138*%
%ADD45C,.066*%
%ADD11C,.039*%
%ADD18R,.07X.07*%
%AMMACRO29*
4,1,8,-.05906,.02362,
.05906,.02362,
.05906,-.02362,
.00394,-.02362,
.00394,.01862,
-.00394,.01862,
-.00394,-.02362,
-.05906,-.02362,
-.05906,.02362,
0.0*
%
%ADD29MACRO29*%
%ADD44R,.066X.066*%
%AMMACRO23*
4,1,28,-.00748,-.00052,
-.00984,-.00052,
-.00984,-.00603,
-.009782,-.006705,
-.009607,-.007359,
-.009321,-.007974,
-.008933,-.008529,
-.008455,-.009009,
-.0079,-.009398,
-.007286,-.009685,
-.006632,-.009861,
-.005957,-.00992,
-.00591,-.00992,
.00591,-.00992,
.006585,-.009869,
.007242,-.009701,
.007859,-.009421,
.008418,-.009039,
.008903,-.008565,
.009297,-.008015,
.009591,-.007404,
.009773,-.006751,
.00984,-.006077,
.00984,-.00603,
.00984,-.00052,
.00748,-.00052,
.00748,.00991,
-.00748,.00991,
-.00748,-.00052,
0.0*
%
%ADD23MACRO23*%
%AMMACRO56*
4,1,5,.00492,.01673,
-.00492,.01673,
-.00492,-.01673,
.00098,-.01673,
.00492,-.0128,
.00492,.01673,
0.0*
%
%ADD56MACRO56*%
%AMMACRO41*
4,1,28,-.00052,.00748,
-.00052,.00984,
-.00603,.00984,
-.006705,.009782,
-.007359,.009607,
-.007974,.009321,
-.008529,.008933,
-.009009,.008455,
-.009398,.0079,
-.009685,.007286,
-.009861,.006632,
-.00992,.005957,
-.00992,.00591,
-.00992,-.00591,
-.009869,-.006585,
-.009701,-.007242,
-.009421,-.007859,
-.009039,-.008418,
-.008565,-.008903,
-.008015,-.009297,
-.007404,-.009591,
-.006751,-.009773,
-.006077,-.00984,
-.00603,-.00984,
-.00052,-.00984,
-.00052,-.00748,
.00991,-.00748,
.00991,.00748,
-.00052,.00748,
0.0*
%
%ADD41MACRO41*%
%AMMACRO27*
4,1,28,-.00748,.00051,
-.00984,.00051,
-.00984,.00602,
-.009782,.006695,
-.009607,.007349,
-.009321,.007964,
-.008933,.008519,
-.008455,.008998,
-.0079,.009388,
-.007287,.009675,
-.006632,.009851,
-.005958,.00991,
-.00591,.00991,
.00591,.00991,
.006585,.009859,
.007242,.009691,
.007859,.009411,
.008418,.009029,
.008903,.008555,
.009297,.008005,
.00959,.007394,
.009773,.006742,
.00984,.006068,
.00984,.00602,
.00984,.00051,
.00748,.00051,
.00748,-.00992,
-.00748,-.00992,
-.00748,.00051,
0.0*
%
%ADD27MACRO27*%
%AMMACRO40*
4,1,28,.00051,.00748,
.00051,.00984,
.00602,.00984,
.006695,.009782,
.007349,.009607,
.007964,.009321,
.008519,.008933,
.008998,.008455,
.009388,.0079,
.009675,.007287,
.009851,.006632,
.00991,.005958,
.00991,.00591,
.00991,-.00591,
.009859,-.006585,
.009691,-.007242,
.009411,-.007859,
.009029,-.008418,
.008555,-.008903,
.008005,-.009297,
.007394,-.00959,
.006742,-.009773,
.006068,-.00984,
.00602,-.00984,
.00051,-.00984,
.00051,-.00748,
-.00992,-.00748,
-.00992,.00748,
.00051,.00748,
0.0*
%
%ADD40MACRO40*%
%AMMACRO55*
4,1,8,-.01821,.0246,
.01821,.0246,
.01821,.01476,
-.00837,.01476,
-.00837,-.01477,
.01821,-.01477,
.01821,-.02461,
-.01821,-.02461,
-.01821,.0246,
0.0*
%
%ADD55MACRO55*%
%AMMACRO68*
4,1,5,.01772,.00591,
-.01772,.00591,
-.01772,0.0,
-.01181,-.00591,
.01772,-.00591,
.01772,.00591,
0.0*
%
%ADD68MACRO68*%
%ADD35R,.01X.02*%
%ADD52R,.032X.01*%
%ADD53R,.01X.032*%
%ADD51R,.01X.05*%
%ADD66R,.032X.012*%
%ADD42R,.032X.022*%
%ADD20R,.05X.04*%
%ADD69R,.04X.05*%
%ADD50R,.02X.018*%
%ADD21R,.032X.024*%
%ADD32R,.018X.02*%
%ADD22R,.063X.04*%
%ADD10C,.4*%
%ADD43R,.036X.032*%
%ADD33R,.126X.27*%
%ADD13R,.04X.063*%
%ADD46R,.032X.036*%
%ADD39R,.017X.024*%
%ADD34R,.032X.028*%
%ADD62R,.028X.024*%
%ADD61R,.052X.018*%
%ADD60R,.056X.014*%
%ADD30R,.028X.032*%
%ADD38R,.054X.044*%
%ADD14R,.024X.028*%
%ADD65R,.138X.128*%
%ADD59R,.068X.022*%
%ADD28R,.044X.054*%
%ADD58R,.022X.068*%
%ADD54R,.059X.014*%
%ADD67R,.012X.079*%
%ADD72R,.042X.099*%
%ADD57R,.089X.085*%
%AMMACRO37*
4,1,28,.00052,-.00748,
.00052,-.00984,
.00603,-.00984,
.006705,-.009782,
.007359,-.009607,
.007974,-.009321,
.008529,-.008933,
.009009,-.008455,
.009398,-.0079,
.009685,-.007286,
.009861,-.006632,
.00992,-.005957,
.00992,-.00591,
.00992,.00591,
.009869,.006585,
.009701,.007242,
.009421,.007859,
.009039,.008418,
.008565,.008903,
.008015,.009297,
.007404,.009591,
.006751,.009773,
.006077,.00984,
.00603,.00984,
.00052,.00984,
.00052,.00748,
-.00991,.00748,
-.00991,-.00748,
.00052,-.00748,
0.0*
%
%ADD37MACRO37*%
%AMMACRO25*
4,1,28,.00748,.00052,
.00984,.00052,
.00984,.00603,
.009782,.006705,
.009607,.007359,
.009321,.007974,
.008933,.008529,
.008455,.009009,
.0079,.009398,
.007286,.009685,
.006632,.009861,
.005957,.00992,
.00591,.00992,
-.00591,.00992,
-.006585,.009869,
-.007242,.009701,
-.007859,.009421,
-.008418,.009039,
-.008903,.008565,
-.009297,.008015,
-.009591,.007404,
-.009773,.006751,
-.00984,.006077,
-.00984,.00603,
-.00984,.00052,
-.00748,.00052,
-.00748,-.00991,
.00748,-.00991,
.00748,.00052,
0.0*
%
%ADD25MACRO25*%
%ADD49R,.099X.067*%
%AMMACRO48*
4,1,8,.05906,-.02362,
-.05906,-.02362,
-.05906,.02362,
-.00394,.02362,
-.00394,-.01862,
.00394,-.01862,
.00394,.02362,
.05906,.02362,
.05906,-.02362,
0.0*
%
%ADD48MACRO48*%
%AMMACRO15*
4,1,8,-.02362,-.05906,
-.02362,.05906,
.02362,.05906,
.02362,.00394,
-.01862,.00394,
-.01862,-.00394,
.02362,-.00394,
.02362,-.05906,
-.02362,-.05906,
0.0*
%
%ADD15MACRO15*%
%AMMACRO36*
4,1,28,-.00051,-.00748,
-.00051,-.00984,
-.00602,-.00984,
-.006695,-.009782,
-.007349,-.009607,
-.007964,-.009321,
-.008519,-.008933,
-.008998,-.008455,
-.009388,-.0079,
-.009675,-.007287,
-.009851,-.006632,
-.00991,-.005958,
-.00991,-.00591,
-.00991,.00591,
-.009859,.006585,
-.009691,.007242,
-.009411,.007859,
-.009029,.008418,
-.008555,.008903,
-.008005,.009297,
-.007394,.00959,
-.006742,.009773,
-.006068,.00984,
-.00602,.00984,
-.00051,.00984,
-.00051,.00748,
.00992,.00748,
.00992,-.00748,
-.00051,-.00748,
0.0*
%
%ADD36MACRO36*%
%AMMACRO24*
4,1,28,.00748,-.00051,
.00984,-.00051,
.00984,-.00602,
.009782,-.006695,
.009607,-.007349,
.009321,-.007964,
.008933,-.008519,
.008455,-.008998,
.0079,-.009388,
.007287,-.009675,
.006632,-.009851,
.005958,-.00991,
.00591,-.00991,
-.00591,-.00991,
-.006585,-.009859,
-.007242,-.009691,
-.007859,-.009411,
-.008418,-.009029,
-.008903,-.008555,
-.009297,-.008005,
-.00959,-.007394,
-.009773,-.006742,
-.00984,-.006068,
-.00984,-.00602,
-.00984,-.00051,
-.00748,-.00051,
-.00748,.00992,
.00748,.00992,
.00748,-.00051,
0.0*
%
%ADD24MACRO24*%
%ADD74C,.006*%
G75*
%LPD*%
G75*
G54D10*
X32284Y541339D03*
X59055Y498032D03*
X1673228D03*
X1700000Y541339D03*
G54D20*
X191885Y119000D03*
X200685Y115000D03*
Y123000D03*
X490384Y325500D03*
X499184Y329500D03*
Y321500D03*
X1263100Y329500D03*
X1271900Y333500D03*
X1263100Y337500D03*
X1539900Y112500D03*
X1531100Y108500D03*
Y116500D03*
X1762100Y241500D03*
Y248500D03*
X1771100Y241500D03*
Y248500D03*
X1779600Y241500D03*
Y248500D03*
G54D11*
X99149Y604098D03*
X1024887Y231919D03*
X1641531Y219808D03*
X1716930Y503124D03*
G54D30*
X444838Y87700D03*
Y81900D03*
Y132100D03*
Y126300D03*
Y176500D03*
Y170700D03*
Y220900D03*
Y215100D03*
Y265300D03*
Y259500D03*
Y309700D03*
Y303900D03*
X668000Y320900D03*
Y315100D03*
X1317446Y67900D03*
Y62100D03*
Y112300D03*
Y106500D03*
Y156700D03*
Y150900D03*
Y201100D03*
Y195300D03*
Y239700D03*
Y245500D03*
Y289900D03*
Y284100D03*
G54D21*
X190950Y106500D03*
X197250Y109059D03*
Y103941D03*
X1541150Y99500D03*
X1534850Y96941D03*
Y102059D03*
G54D12*
X124600Y120500D03*
X120840Y145500D03*
X121100Y163500D03*
X206900Y110700D03*
X202924Y102925D03*
X254000Y141000D03*
X263000D03*
X325100Y64000D03*
X439400Y81900D03*
X439500Y126300D03*
X436500Y175600D03*
X437200Y219100D03*
X438800Y259500D03*
X439100Y303900D03*
X484100Y325500D03*
X485300Y332100D03*
X536000Y57000D03*
X548000Y68000D03*
X547000Y87000D03*
X543000Y172000D03*
X533000Y156000D03*
X547000Y195000D03*
X546000Y215000D03*
X537000Y227000D03*
X534000Y275000D03*
X564305Y160784D03*
X590298Y282890D03*
X571325Y292757D03*
X590298Y276984D03*
X612684Y297000D03*
X606084Y293100D03*
X616684Y307975D03*
X622184Y308000D03*
X608259Y305000D03*
X639010Y236377D03*
X645900Y242200D03*
X650500Y246600D03*
X637684Y280575D03*
X625684Y273499D03*
X630308Y284500D03*
X649500Y308500D03*
X674800Y269600D03*
X671400Y261000D03*
X666759Y274800D03*
X679184Y273190D03*
X671000Y331925D03*
X685884Y297000D03*
X736554Y131056D03*
X742554Y128056D03*
X726100Y185000D03*
X717384Y273400D03*
X718000Y300000D03*
X714045Y326886D03*
X809400Y362200D03*
X923100D03*
X980500Y185000D03*
X996954Y128056D03*
X1027675Y215000D03*
X1044900Y278600D03*
X1074430Y256461D03*
X1091800Y279100D03*
X1083100Y278810D03*
X1090200Y288600D03*
X1131976Y267500D03*
X1133100Y277700D03*
X1123100Y322500D03*
X1112136Y305400D03*
X1123400Y356300D03*
X1145600Y257500D03*
X1156200Y258900D03*
X1145600Y244025D03*
X1140100Y244000D03*
X1163266Y255311D03*
X1171600Y238000D03*
X1171986Y269110D03*
X1187700Y288000D03*
X1196500Y293284D03*
X1171986Y275016D03*
X1179500Y355000D03*
X1214000Y83000D03*
X1223000Y96000D03*
X1200575Y160284D03*
X1225000Y165000D03*
X1214000Y177000D03*
X1223000Y197000D03*
X1212000Y215000D03*
X1227000Y223000D03*
X1226000Y251000D03*
X1201500Y293284D03*
X1199100Y273500D03*
X1228000Y274000D03*
X1278200Y329500D03*
X1263100Y343200D03*
X1323900Y62100D03*
X1323500Y106500D03*
X1324000Y156000D03*
Y199000D03*
X1323700Y239700D03*
X1323000Y284100D03*
X1406230Y21076D03*
X1400230Y15076D03*
X1498180Y63500D03*
X1529400Y102075D03*
X1524600Y119500D03*
X1607100Y115000D03*
X1618177Y120474D03*
X1611100Y138500D03*
X1612100Y154000D03*
X1620500Y170500D03*
X1620000Y177500D03*
X1630527Y90564D03*
X1646500Y94000D03*
X1627366Y143500D03*
X1622388Y127365D03*
X1634200Y180500D03*
X1636600Y173500D03*
X1621500Y159000D03*
Y165000D03*
X1636500Y168000D03*
Y162500D03*
X1648925Y194000D03*
X1635163Y200500D03*
X1674600Y176000D03*
X1674100Y168280D03*
X1673600Y158500D03*
X1657500Y191500D03*
X1667600Y198500D03*
X1690100Y116000D03*
X1708075Y124025D03*
X1710000Y203500D03*
X1714100Y104500D03*
X1724600Y119500D03*
Y134500D03*
X1726100Y148780D03*
X1726600Y168500D03*
X1724922Y245500D03*
X1761100Y104500D03*
X1760500Y119500D03*
X1761600Y129500D03*
X1758600Y148780D03*
X1759000Y140000D03*
X1758600Y164280D03*
X1759000Y156000D03*
X1755000Y174000D03*
X1744500Y187500D03*
X1763000Y200500D03*
X1749000Y416000D03*
X1778000Y200500D03*
X1809600Y195000D03*
G36*
G01X486551Y86467D02*
X492457D01*
Y79774D01*
X489754D01*
Y78987D01*
X492457D01*
Y72294D01*
X489754D01*
Y71506D01*
X492457D01*
Y64813D01*
X489754D01*
Y64026D01*
X492457D01*
Y60930D01*
X498756D01*
Y64026D01*
X501459D01*
Y64813D01*
X498756D01*
Y71506D01*
X501459D01*
Y72294D01*
X498756D01*
Y78987D01*
X501459D01*
Y79774D01*
X498756D01*
Y86467D01*
X504661D01*
Y79774D01*
X501959D01*
Y78987D01*
X504661D01*
Y72294D01*
X501959D01*
Y71506D01*
X504661D01*
Y64813D01*
X501959D01*
Y64026D01*
X504661D01*
Y60930D01*
X510961D01*
Y64223D01*
X514943D01*
Y65404D01*
X510961D01*
Y71309D01*
X514943D01*
Y72491D01*
X510961D01*
Y78396D01*
X514943D01*
Y79577D01*
X510961D01*
Y85483D01*
X514943D01*
Y86664D01*
X510961D01*
Y92569D01*
X519425D01*
Y86664D01*
X515443D01*
Y85483D01*
X519425D01*
Y79577D01*
X515443D01*
Y78396D01*
X519425D01*
Y72491D01*
X515443D01*
Y71309D01*
X519425D01*
Y65404D01*
X515443D01*
Y64223D01*
X519425D01*
Y58317D01*
X515443D01*
Y57136D01*
X519425D01*
Y51231D01*
X510961D01*
Y57136D01*
X514943D01*
Y58317D01*
X510961D01*
Y60430D01*
X504661D01*
Y57333D01*
X498756D01*
Y60430D01*
X492457D01*
Y57333D01*
X486551D01*
Y64026D01*
X489254D01*
Y64813D01*
X486551D01*
Y71506D01*
X489254D01*
Y72294D01*
X486551D01*
Y78987D01*
X489254D01*
Y79774D01*
X486551D01*
Y86467D01*
G37*
G36*
G01Y130867D02*
X492457D01*
Y124174D01*
X489754D01*
Y123387D01*
X492457D01*
Y116694D01*
X489754D01*
Y115906D01*
X492457D01*
Y109213D01*
X489754D01*
Y108426D01*
X492457D01*
Y105330D01*
X498756D01*
Y108426D01*
X501459D01*
Y109213D01*
X498756D01*
Y115906D01*
X501459D01*
Y116694D01*
X498756D01*
Y123387D01*
X501459D01*
Y124174D01*
X498756D01*
Y130867D01*
X504661D01*
Y124174D01*
X501959D01*
Y123387D01*
X504661D01*
Y116694D01*
X501959D01*
Y115906D01*
X504661D01*
Y109213D01*
X501959D01*
Y108426D01*
X504661D01*
Y105330D01*
X510961D01*
Y108623D01*
X514943D01*
Y109804D01*
X510961D01*
Y115709D01*
X514943D01*
Y116891D01*
X510961D01*
Y122796D01*
X514943D01*
Y123977D01*
X510961D01*
Y129883D01*
X514943D01*
Y131064D01*
X510961D01*
Y136969D01*
X519425D01*
Y131064D01*
X515443D01*
Y129883D01*
X519425D01*
Y123977D01*
X515443D01*
Y122796D01*
X519425D01*
Y116891D01*
X515443D01*
Y115709D01*
X519425D01*
Y109804D01*
X515443D01*
Y108623D01*
X519425D01*
Y102717D01*
X515443D01*
Y101536D01*
X519425D01*
Y95631D01*
X510961D01*
Y101536D01*
X514943D01*
Y102717D01*
X510961D01*
Y104830D01*
X504661D01*
Y101733D01*
X498756D01*
Y104830D01*
X492457D01*
Y101733D01*
X486551D01*
Y108426D01*
X489254D01*
Y109213D01*
X486551D01*
Y115906D01*
X489254D01*
Y116694D01*
X486551D01*
Y123387D01*
X489254D01*
Y124174D01*
X486551D01*
Y130867D01*
G37*
G36*
G01Y175267D02*
X492457D01*
Y168574D01*
X489754D01*
Y167787D01*
X492457D01*
Y161094D01*
X489754D01*
Y160306D01*
X492457D01*
Y153613D01*
X489754D01*
Y152826D01*
X492457D01*
Y149730D01*
X498756D01*
Y152826D01*
X501459D01*
Y153613D01*
X498756D01*
Y160306D01*
X501459D01*
Y161094D01*
X498756D01*
Y167787D01*
X501459D01*
Y168574D01*
X498756D01*
Y175267D01*
X504661D01*
Y168574D01*
X501959D01*
Y167787D01*
X504661D01*
Y161094D01*
X501959D01*
Y160306D01*
X504661D01*
Y153613D01*
X501959D01*
Y152826D01*
X504661D01*
Y149730D01*
X510961D01*
Y153023D01*
X514943D01*
Y154204D01*
X510961D01*
Y160109D01*
X514943D01*
Y161291D01*
X510961D01*
Y167196D01*
X514943D01*
Y168377D01*
X510961D01*
Y174283D01*
X514943D01*
Y175464D01*
X510961D01*
Y181369D01*
X519425D01*
Y175464D01*
X515443D01*
Y174283D01*
X519425D01*
Y168377D01*
X515443D01*
Y167196D01*
X519425D01*
Y161291D01*
X515443D01*
Y160109D01*
X519425D01*
Y154204D01*
X515443D01*
Y153023D01*
X519425D01*
Y147117D01*
X515443D01*
Y145936D01*
X519425D01*
Y140031D01*
X510961D01*
Y145936D01*
X514943D01*
Y147117D01*
X510961D01*
Y149230D01*
X504661D01*
Y146133D01*
X498756D01*
Y149230D01*
X492457D01*
Y146133D01*
X486551D01*
Y152826D01*
X489254D01*
Y153613D01*
X486551D01*
Y160306D01*
X489254D01*
Y161094D01*
X486551D01*
Y167787D01*
X489254D01*
Y168574D01*
X486551D01*
Y175267D01*
G37*
G36*
G01Y219667D02*
X492457D01*
Y212974D01*
X489754D01*
Y212187D01*
X492457D01*
Y205494D01*
X489754D01*
Y204706D01*
X492457D01*
Y198013D01*
X489754D01*
Y197226D01*
X492457D01*
Y194130D01*
X498756D01*
Y197226D01*
X501459D01*
Y198013D01*
X498756D01*
Y204706D01*
X501459D01*
Y205494D01*
X498756D01*
Y212187D01*
X501459D01*
Y212974D01*
X498756D01*
Y219667D01*
X504661D01*
Y212974D01*
X501959D01*
Y212187D01*
X504661D01*
Y205494D01*
X501959D01*
Y204706D01*
X504661D01*
Y198013D01*
X501959D01*
Y197226D01*
X504661D01*
Y194130D01*
X510961D01*
Y197423D01*
X514943D01*
Y198604D01*
X510961D01*
Y204509D01*
X514943D01*
Y205691D01*
X510961D01*
Y211596D01*
X514943D01*
Y212777D01*
X510961D01*
Y218683D01*
X514943D01*
Y219864D01*
X510961D01*
Y225769D01*
X519425D01*
Y219864D01*
X515443D01*
Y218683D01*
X519425D01*
Y212777D01*
X515443D01*
Y211596D01*
X519425D01*
Y205691D01*
X515443D01*
Y204509D01*
X519425D01*
Y198604D01*
X515443D01*
Y197423D01*
X519425D01*
Y191517D01*
X515443D01*
Y190336D01*
X519425D01*
Y184431D01*
X510961D01*
Y190336D01*
X514943D01*
Y191517D01*
X510961D01*
Y193630D01*
X504661D01*
Y190533D01*
X498756D01*
Y193630D01*
X492457D01*
Y190533D01*
X486551D01*
Y197226D01*
X489254D01*
Y198013D01*
X486551D01*
Y204706D01*
X489254D01*
Y205494D01*
X486551D01*
Y212187D01*
X489254D01*
Y212974D01*
X486551D01*
Y219667D01*
G37*
G36*
G01Y264067D02*
X492457D01*
Y257374D01*
X489754D01*
Y256587D01*
X492457D01*
Y249894D01*
X489754D01*
Y249106D01*
X492457D01*
Y242413D01*
X489754D01*
Y241626D01*
X492457D01*
Y238530D01*
X498756D01*
Y241626D01*
X501459D01*
Y242413D01*
X498756D01*
Y249106D01*
X501459D01*
Y249894D01*
X498756D01*
Y256587D01*
X501459D01*
Y257374D01*
X498756D01*
Y264067D01*
X504661D01*
Y257374D01*
X501959D01*
Y256587D01*
X504661D01*
Y249894D01*
X501959D01*
Y249106D01*
X504661D01*
Y242413D01*
X501959D01*
Y241626D01*
X504661D01*
Y238530D01*
X510961D01*
Y241823D01*
X514943D01*
Y243004D01*
X510961D01*
Y248909D01*
X514943D01*
Y250091D01*
X510961D01*
Y255996D01*
X514943D01*
Y257177D01*
X510961D01*
Y263083D01*
X514943D01*
Y264264D01*
X510961D01*
Y270169D01*
X519425D01*
Y264264D01*
X515443D01*
Y263083D01*
X519425D01*
Y257177D01*
X515443D01*
Y255996D01*
X519425D01*
Y250091D01*
X515443D01*
Y248909D01*
X519425D01*
Y243004D01*
X515443D01*
Y241823D01*
X519425D01*
Y235917D01*
X515443D01*
Y234736D01*
X519425D01*
Y228831D01*
X510961D01*
Y234736D01*
X514943D01*
Y235917D01*
X510961D01*
Y238030D01*
X504661D01*
Y234933D01*
X498756D01*
Y238030D01*
X492457D01*
Y234933D01*
X486551D01*
Y241626D01*
X489254D01*
Y242413D01*
X486551D01*
Y249106D01*
X489254D01*
Y249894D01*
X486551D01*
Y256587D01*
X489254D01*
Y257374D01*
X486551D01*
Y264067D01*
G37*
G36*
G01Y308467D02*
X492457D01*
Y301774D01*
X489754D01*
Y300987D01*
X492457D01*
Y294294D01*
X489754D01*
Y293506D01*
X492457D01*
Y286813D01*
X489754D01*
Y286026D01*
X492457D01*
Y282930D01*
X498756D01*
Y286026D01*
X501459D01*
Y286813D01*
X498756D01*
Y293506D01*
X501459D01*
Y294294D01*
X498756D01*
Y300987D01*
X501459D01*
Y301774D01*
X498756D01*
Y308467D01*
X504661D01*
Y301774D01*
X501959D01*
Y300987D01*
X504661D01*
Y294294D01*
X501959D01*
Y293506D01*
X504661D01*
Y286813D01*
X501959D01*
Y286026D01*
X504661D01*
Y282930D01*
X510961D01*
Y286223D01*
X514943D01*
Y287404D01*
X510961D01*
Y293309D01*
X514943D01*
Y294491D01*
X510961D01*
Y300396D01*
X514943D01*
Y301577D01*
X510961D01*
Y307483D01*
X514943D01*
Y308664D01*
X510961D01*
Y314569D01*
X519425D01*
Y308664D01*
X515443D01*
Y307483D01*
X519425D01*
Y301577D01*
X515443D01*
Y300396D01*
X519425D01*
Y294491D01*
X515443D01*
Y293309D01*
X519425D01*
Y287404D01*
X515443D01*
Y286223D01*
X519425D01*
Y280317D01*
X515443D01*
Y279136D01*
X519425D01*
Y273231D01*
X510961D01*
Y279136D01*
X514943D01*
Y280317D01*
X510961D01*
Y282430D01*
X504661D01*
Y279333D01*
X498756D01*
Y282430D01*
X492457D01*
Y279333D01*
X486551D01*
Y286026D01*
X489254D01*
Y286813D01*
X486551D01*
Y293506D01*
X489254D01*
Y294294D01*
X486551D01*
Y300987D01*
X489254D01*
Y301774D01*
X486551D01*
Y308467D01*
G37*
G54D13*
X126986Y145500D03*
Y136500D03*
Y127500D03*
Y163500D03*
Y154500D03*
X139584Y145500D03*
Y136500D03*
Y127500D03*
Y163500D03*
Y154500D03*
X1592701Y149000D03*
X1605299D03*
Y140000D03*
X1592701D03*
Y131000D03*
X1605299D03*
Y122000D03*
X1592701D03*
X1605299Y158000D03*
X1592701D03*
G54D22*
X192600Y130201D03*
Y142799D03*
X1539600Y123701D03*
Y136299D03*
G54D40*
X666668Y260500D03*
Y264500D03*
X680584Y302500D03*
X695084Y255500D03*
Y251500D03*
X1085584Y255500D03*
X1098584Y296000D03*
Y300500D03*
X1108084Y291500D03*
Y285000D03*
X1118084Y296000D03*
X1108084Y300500D03*
X1200484Y155300D03*
Y288500D03*
X1524984Y114500D03*
X1615484Y173000D03*
Y169500D03*
Y165500D03*
X1627754Y115140D03*
X1635084Y142000D03*
X1629484Y183000D03*
X1655484Y199000D03*
X1667984Y186500D03*
X1683484Y148000D03*
Y175500D03*
Y153500D03*
Y159000D03*
Y164500D03*
Y170000D03*
Y181000D03*
X1705984Y208000D03*
X1718984Y134500D03*
Y129500D03*
X1720984Y168500D03*
Y153000D03*
X1725984Y179500D03*
X1762984Y174000D03*
X1766984Y153000D03*
Y168500D03*
X1750984Y200500D03*
X1757984D03*
X1770484Y109500D03*
X1770584Y116500D03*
X1770484Y104500D03*
X1770584Y120500D03*
X1770484Y134500D03*
X1772484Y200500D03*
X1774794Y328322D03*
X1770764Y322670D03*
X1777784Y322700D03*
X1774892Y348288D03*
X1774794Y332322D03*
G54D14*
X134655Y120500D03*
X130915D03*
X1597630Y115000D03*
X1601370D03*
G54D32*
X515009Y329000D03*
X511859D03*
D03*
X508709D03*
X511859Y322000D03*
X508709D03*
X511859D03*
X515009D03*
X1247275Y330000D03*
X1250425D03*
D03*
X1253575D03*
X1250425Y337000D03*
X1253575D03*
X1250425D03*
X1247275D03*
X1635195Y90940D03*
X1638345D03*
X1654615Y102380D03*
X1651465D03*
X1762454Y322905D03*
X1759304D03*
X1771833Y352305D03*
X1774983D03*
G54D50*
X1620960Y111232D03*
Y108082D03*
X1624940Y111232D03*
Y108082D03*
X1662000Y108425D03*
Y111575D03*
G54D41*
X663701Y260500D03*
Y264500D03*
X677617Y302500D03*
X692117Y255500D03*
Y251500D03*
X1082617Y255500D03*
X1095617Y296000D03*
Y300500D03*
X1105117Y291500D03*
Y285000D03*
X1115117Y296000D03*
X1105117Y300500D03*
X1197517Y155300D03*
Y288500D03*
X1522017Y114500D03*
X1612517Y173000D03*
Y169500D03*
Y165500D03*
X1624787Y115140D03*
X1632117Y142000D03*
X1626517Y183000D03*
X1652517Y199000D03*
X1665017Y186500D03*
X1680517Y148000D03*
Y175500D03*
Y153500D03*
Y159000D03*
Y164500D03*
Y170000D03*
Y181000D03*
X1703017Y208000D03*
X1716017Y134500D03*
Y129500D03*
X1718017Y168500D03*
Y153000D03*
X1723017Y179500D03*
X1767517Y109500D03*
X1767617Y116500D03*
X1767517Y104500D03*
X1767617Y120500D03*
X1767517Y134500D03*
X1760017Y174000D03*
X1764017Y153000D03*
Y168500D03*
X1748017Y200500D03*
X1755017D03*
X1769517D03*
X1767797Y322670D03*
X1771827Y328322D03*
X1774817Y322700D03*
X1771925Y348288D03*
X1771827Y332322D03*
G54D23*
X208000Y115517D03*
X330500Y69017D03*
X326000D03*
X649500Y257517D03*
X653500Y327017D03*
X676500Y332017D03*
X680500D03*
X1037600Y189017D03*
X1499228Y69018D03*
X1503728D03*
X1524500Y99017D03*
X1628960Y108174D03*
X1627770Y127457D03*
X1645280Y127517D03*
X1638770Y127457D03*
X1631770D03*
X1641000Y201517D03*
X1629600Y192517D03*
X1649270Y127457D03*
X1690100Y132917D03*
X1700100Y121917D03*
X1707200Y160517D03*
X1721000Y145017D03*
Y160517D03*
X1764000Y145017D03*
Y160517D03*
X1746102Y328540D03*
X1852164Y421755D03*
X1837164D03*
X1847164D03*
X1842164D03*
G54D24*
X208000Y103016D03*
X317000Y69016D03*
X321500D03*
X392000Y43816D03*
X663500Y314516D03*
X732000Y307516D03*
X1490228Y69017D03*
X1494728D03*
X1622100Y149016D03*
X1618500Y182516D03*
X1653270Y127456D03*
X1690100Y121916D03*
X1685100D03*
X1707500Y195516D03*
X1711600Y145016D03*
X1717100D03*
X1712000Y160516D03*
X1716500D03*
X1768500Y145016D03*
Y160516D03*
X1773000Y145016D03*
Y160516D03*
X1778000Y192516D03*
X1786600Y243516D03*
X1775816Y336590D03*
X1771816D03*
X1779816D03*
G54D15*
X156785Y110251D03*
X176785D03*
X1555500Y104251D03*
X1575500D03*
G54D60*
X1733711Y143661D03*
Y146220D03*
Y159161D03*
Y161720D03*
Y164280D03*
Y166839D03*
Y148780D03*
Y151339D03*
X1751289Y146220D03*
Y143661D03*
Y166839D03*
Y164280D03*
Y161720D03*
Y159161D03*
Y151339D03*
Y148780D03*
G54D33*
X554149Y116300D03*
Y249500D03*
X571865Y116300D03*
Y249500D03*
X1190419Y116300D03*
Y249500D03*
X1208135Y116300D03*
Y249500D03*
G54D42*
X674276Y315760D03*
Y319500D03*
Y323240D03*
X683724D03*
Y315760D03*
X1715376Y194760D03*
Y202240D03*
X1724824D03*
Y198500D03*
Y194760D03*
G54D51*
X1637601Y113200D03*
X1641144D03*
X1644687D03*
X1648231D03*
G36*
G01X152218Y134464D02*
Y140370D01*
X158911D01*
Y137667D01*
X159698D01*
Y140370D01*
X166391D01*
Y137667D01*
X167179D01*
Y140370D01*
X173872D01*
Y137667D01*
X174659D01*
Y140370D01*
X177755D01*
Y146669D01*
X174659D01*
Y149372D01*
X173872D01*
Y146669D01*
X167179D01*
Y149372D01*
X166391D01*
Y146669D01*
X159698D01*
Y149372D01*
X158911D01*
Y146669D01*
X152218D01*
Y152574D01*
X158911D01*
Y149872D01*
X159698D01*
Y152574D01*
X166391D01*
Y149872D01*
X167179D01*
Y152574D01*
X173872D01*
Y149872D01*
X174659D01*
Y152574D01*
X177755D01*
Y158874D01*
X174462D01*
Y162856D01*
X173281D01*
Y158874D01*
X167376D01*
Y162856D01*
X166194D01*
Y158874D01*
X160289D01*
Y162856D01*
X159108D01*
Y158874D01*
X153202D01*
Y162856D01*
X152021D01*
Y158874D01*
X146116D01*
Y167338D01*
X152021D01*
Y163356D01*
X153202D01*
Y167338D01*
X159108D01*
Y163356D01*
X160289D01*
Y167338D01*
X166194D01*
Y163356D01*
X167376D01*
Y167338D01*
X173281D01*
Y163356D01*
X174462D01*
Y167338D01*
X180368D01*
Y163356D01*
X181549D01*
Y167338D01*
X187454D01*
Y158874D01*
X181549D01*
Y162856D01*
X180368D01*
Y158874D01*
X178255D01*
Y152574D01*
X181352D01*
Y146669D01*
X178255D01*
Y140370D01*
X181352D01*
Y134464D01*
X174659D01*
Y137167D01*
X173872D01*
Y134464D01*
X167179D01*
Y137167D01*
X166391D01*
Y134464D01*
X159698D01*
Y137167D01*
X158911D01*
Y134464D01*
X152218D01*
G37*
G36*
G01X1550933Y128464D02*
Y134370D01*
X1557626D01*
Y131667D01*
X1558413D01*
Y134370D01*
X1565106D01*
Y131667D01*
X1565894D01*
Y134370D01*
X1572587D01*
Y131667D01*
X1573374D01*
Y134370D01*
X1576470D01*
Y140669D01*
X1573374D01*
Y143372D01*
X1572587D01*
Y140669D01*
X1565894D01*
Y143372D01*
X1565106D01*
Y140669D01*
X1558413D01*
Y143372D01*
X1557626D01*
Y140669D01*
X1550933D01*
Y146574D01*
X1557626D01*
Y143872D01*
X1558413D01*
Y146574D01*
X1565106D01*
Y143872D01*
X1565894D01*
Y146574D01*
X1572587D01*
Y143872D01*
X1573374D01*
Y146574D01*
X1576470D01*
Y152874D01*
X1573177D01*
Y156856D01*
X1571996D01*
Y152874D01*
X1566091D01*
Y156856D01*
X1564909D01*
Y152874D01*
X1559004D01*
Y156856D01*
X1557823D01*
Y152874D01*
X1551917D01*
Y156856D01*
X1550736D01*
Y152874D01*
X1544831D01*
Y161338D01*
X1550736D01*
Y157356D01*
X1551917D01*
Y161338D01*
X1557823D01*
Y157356D01*
X1559004D01*
Y161338D01*
X1564909D01*
Y157356D01*
X1566091D01*
Y161338D01*
X1571996D01*
Y157356D01*
X1573177D01*
Y161338D01*
X1579083D01*
Y157356D01*
X1580264D01*
Y161338D01*
X1586169D01*
Y152874D01*
X1580264D01*
Y156856D01*
X1579083D01*
Y152874D01*
X1576970D01*
Y146574D01*
X1580067D01*
Y140669D01*
X1576970D01*
Y134370D01*
X1580067D01*
Y128464D01*
X1573374D01*
Y131167D01*
X1572587D01*
Y128464D01*
X1565894D01*
Y131167D01*
X1565106D01*
Y128464D01*
X1558413D01*
Y131167D01*
X1557626D01*
Y128464D01*
X1550933D01*
G37*
G54D25*
X208000Y105983D03*
X317000Y71983D03*
X321500D03*
X392000Y46783D03*
X663500Y317483D03*
X732000Y310483D03*
X1490228Y71984D03*
X1494728D03*
X1622100Y151983D03*
X1618500Y185483D03*
X1653270Y130423D03*
X1690100Y124883D03*
X1685100D03*
X1707500Y198483D03*
X1711600Y147983D03*
X1717100D03*
X1712000Y163483D03*
X1716500D03*
X1768500Y147983D03*
Y163483D03*
X1773000Y147983D03*
Y163483D03*
X1778000Y195483D03*
X1786600Y246483D03*
X1775816Y339557D03*
X1771816D03*
X1779816D03*
G54D61*
X1737677Y177500D03*
Y173760D03*
Y181240D03*
X1747323Y173760D03*
Y181240D03*
G54D34*
X551430Y135300D03*
X557230D03*
Y142300D03*
X551430D03*
X557230Y149300D03*
X551430D03*
X557230Y268500D03*
X551430D03*
X557230Y282500D03*
X551430D03*
X557230Y275500D03*
X551430D03*
X574230Y135300D03*
X568430D03*
Y142300D03*
X574230D03*
X568430Y149300D03*
X574230D03*
X568430Y268500D03*
X574230D03*
X568430Y282500D03*
X574230D03*
X568430Y275500D03*
X574230D03*
X646900Y251500D03*
X641100D03*
X1114600Y300500D03*
X1120400D03*
X1193500Y135300D03*
X1187700D03*
Y142300D03*
X1193500D03*
Y149300D03*
X1187700D03*
X1193500Y268500D03*
X1187700D03*
X1193500Y282500D03*
X1187700D03*
X1193500Y275500D03*
X1187700D03*
X1204700Y135300D03*
X1210500D03*
Y142300D03*
X1204700D03*
Y149300D03*
X1210500D03*
X1204700Y268500D03*
X1210500D03*
X1204700Y282500D03*
X1210500D03*
X1204700Y275500D03*
X1210500D03*
X1628960Y101030D03*
X1634760D03*
X1628960Y95930D03*
X1634760D03*
G54D43*
X690037Y188000D03*
X682163Y184260D03*
Y191740D03*
X705037Y193500D03*
X697163Y189760D03*
Y197240D03*
X1029063Y201500D03*
X1036937Y205240D03*
Y197760D03*
X1643037Y191000D03*
X1635163Y187260D03*
Y194740D03*
X1758437Y191000D03*
X1750563Y187260D03*
Y194740D03*
X1764563Y187260D03*
Y194740D03*
X1772437Y191000D03*
G54D52*
X1634451Y111232D03*
Y115168D03*
G54D70*
X1751706Y336741D03*
G54D62*
X1731000Y241630D03*
Y245370D03*
G54D53*
X1647837Y107688D03*
X1645868D03*
X1643900D03*
X1641932D03*
X1639963D03*
X1637994D03*
X1636026D03*
Y118712D03*
X1637994D03*
X1639963D03*
X1641932D03*
X1643900D03*
X1645868D03*
X1647837D03*
X1651774Y107688D03*
X1649806D03*
Y118712D03*
G54D35*
X559949Y116300D03*
X566065D03*
X559949Y249500D03*
X566065D03*
X1202335Y116300D03*
X1196219D03*
X1202335Y249500D03*
X1196219D03*
G54D44*
X825900Y362200D03*
X866400Y382200D03*
X906900Y362200D03*
G54D26*
X230685Y115614D03*
Y142386D03*
X1501600Y109614D03*
Y136386D03*
G54D17*
X166785Y200472D03*
Y280472D03*
Y360472D03*
Y440472D03*
Y520472D03*
X243785Y200472D03*
Y280472D03*
Y360472D03*
Y440472D03*
Y520472D03*
X1488500Y200472D03*
Y280472D03*
Y360472D03*
Y440472D03*
Y520472D03*
X1565500Y200472D03*
Y280472D03*
Y360472D03*
Y440472D03*
Y520472D03*
G54D71*
X1762730Y340382D03*
Y338808D03*
Y337233D03*
Y335658D03*
Y334083D03*
Y332508D03*
Y330934D03*
G54D36*
X561246Y155300D03*
Y287500D03*
X601516Y300000D03*
X663700Y256000D03*
X654200Y251500D03*
Y256000D03*
Y260500D03*
Y266000D03*
X663700Y251500D03*
X677616Y298500D03*
X659016Y322500D03*
X688516Y178500D03*
X727327Y300595D03*
X875116Y362000D03*
Y382000D03*
X1066616Y307500D03*
Y311500D03*
X1082616Y251500D03*
X1095616Y291500D03*
Y287500D03*
X1105116Y296000D03*
X1146516Y251500D03*
X1624786Y119140D03*
X1626516Y178000D03*
Y172500D03*
X1628516Y167500D03*
Y163500D03*
X1705016Y134500D03*
Y129500D03*
X1692516Y148000D03*
Y164500D03*
Y170000D03*
Y175500D03*
Y153500D03*
Y159000D03*
Y186500D03*
X1680516D03*
X1692516Y181000D03*
X1724216Y88000D03*
X1713216D03*
X1724216Y99000D03*
Y93500D03*
X1713216Y99000D03*
Y93500D03*
X1716016Y114500D03*
Y109500D03*
Y119500D03*
X1723016Y175000D03*
Y183500D03*
X1732016Y201500D03*
X1711116Y189500D03*
X1729016Y250000D03*
X1767516Y124500D03*
Y129500D03*
X1767016Y174000D03*
X1760016Y181500D03*
X1771796Y343970D03*
X1771916Y356300D03*
G54D72*
X1765686Y396020D03*
X1780056D03*
G54D54*
X1643500Y152925D03*
Y155484D03*
Y158043D03*
Y160602D03*
Y163161D03*
Y165720D03*
Y168280D03*
Y170839D03*
Y173398D03*
Y175957D03*
Y178516D03*
Y181075D03*
X1666500Y178516D03*
Y175957D03*
Y173398D03*
Y170839D03*
Y168280D03*
Y165720D03*
Y163161D03*
Y160602D03*
Y158043D03*
Y155484D03*
Y152925D03*
Y181075D03*
G54D27*
X208000Y118484D03*
X330500Y71984D03*
X326000D03*
X649500Y260484D03*
X653500Y329984D03*
X676500Y334984D03*
X680500D03*
X1037600Y191984D03*
X1499228Y71985D03*
X1503728D03*
X1524500Y101984D03*
X1628960Y111141D03*
X1627770Y130424D03*
X1645280Y130484D03*
X1638770Y130424D03*
X1631770D03*
X1641000Y204484D03*
X1629600Y195484D03*
X1649270Y130424D03*
X1690100Y135884D03*
X1700100Y124884D03*
X1707200Y163484D03*
X1721000Y147984D03*
Y163484D03*
X1764000Y147984D03*
Y163484D03*
X1746102Y331507D03*
X1852164Y424722D03*
X1837164D03*
X1847164D03*
X1842164D03*
G54D18*
X166785Y230000D03*
Y310000D03*
Y390000D03*
Y470000D03*
Y550000D03*
X243785Y230000D03*
Y310000D03*
Y390000D03*
Y470000D03*
Y550000D03*
X1488500Y230000D03*
Y310000D03*
Y390000D03*
Y470000D03*
Y550000D03*
X1565500Y230000D03*
Y310000D03*
Y390000D03*
Y470000D03*
Y550000D03*
G54D45*
X825900Y382200D03*
Y372200D03*
X866400Y362200D03*
Y372200D03*
X906900Y382200D03*
Y372200D03*
G54D63*
X1732870Y392500D03*
X1754130D03*
G54D37*
X564213Y155300D03*
Y287500D03*
X604483Y300000D03*
X666667Y256000D03*
X657167Y251500D03*
Y256000D03*
Y260500D03*
Y266000D03*
X666667Y251500D03*
X680583Y298500D03*
X661983Y322500D03*
X691483Y178500D03*
X730294Y300595D03*
X878083Y362000D03*
Y382000D03*
X1069583Y307500D03*
Y311500D03*
X1085583Y251500D03*
X1098583Y291500D03*
Y287500D03*
X1108083Y296000D03*
X1149483Y251500D03*
X1627753Y119140D03*
X1629483Y178000D03*
Y172500D03*
X1631483Y167500D03*
Y163500D03*
X1707983Y134500D03*
Y129500D03*
X1695483Y148000D03*
Y164500D03*
Y170000D03*
Y175500D03*
Y153500D03*
Y159000D03*
Y186500D03*
X1683483D03*
X1695483Y181000D03*
X1727183Y88000D03*
X1716183D03*
X1727183Y99000D03*
Y93500D03*
X1716183Y99000D03*
Y93500D03*
X1718983Y114500D03*
Y109500D03*
Y119500D03*
X1725983Y175000D03*
Y183500D03*
X1734983Y201500D03*
X1714083Y189500D03*
X1731983Y250000D03*
X1762983Y181500D03*
X1770483Y124500D03*
Y129500D03*
X1769983Y174000D03*
X1774763Y343970D03*
X1774883Y356300D03*
G54D28*
X387060Y55500D03*
X394540D03*
X590760Y318000D03*
X598240D03*
X696760Y178000D03*
X704240D03*
X1031840Y190500D03*
X1024360D03*
X1628840Y202500D03*
X1621360D03*
G54D46*
X1043360Y197437D03*
X1047100Y189563D03*
X1050840Y197437D03*
X1635340Y149063D03*
X1627860D03*
X1631600Y156937D03*
X1735000Y195937D03*
X1738740Y188063D03*
X1731260D03*
G54D55*
X1653103Y113201D03*
G54D19*
X197691Y73000D03*
X176431D03*
X197691Y91000D03*
X176431D03*
X1574870Y67000D03*
Y85000D03*
X1596130Y67000D03*
Y85000D03*
G54D64*
X1746100Y235839D03*
Y253161D03*
G54D73*
X1846142Y230433D03*
Y240433D03*
X1856772D03*
Y230433D03*
X1846142Y250433D03*
Y260433D03*
Y270433D03*
X1856772D03*
Y260433D03*
Y250433D03*
X1846142Y280433D03*
Y290433D03*
Y300433D03*
X1856772D03*
Y290433D03*
Y280433D03*
X1848957Y324213D03*
X1843957Y329213D03*
X1848957Y314213D03*
X1843957Y319213D03*
X1853957Y329213D03*
Y319213D03*
X1858957Y324213D03*
Y314213D03*
X1848957Y334213D03*
Y344213D03*
X1843957Y339213D03*
Y349213D03*
X1853957D03*
Y339213D03*
X1858957Y344213D03*
Y334213D03*
G54D74*
G01X-457143Y-1211429D02*
Y2242857D01*
X4308572D01*
Y-1211429D01*
X-457143D01*
G01X37000Y-995000D02*
Y-1070000D01*
X537000D01*
Y-995000D01*
X37000D01*
G01X49000Y-1060000D02*
Y-1065000D01*
G01X47543Y-1060000D02*
X50457D01*
G01X55367Y-1065000D02*
X52833D01*
Y-1060000D01*
X55367D01*
G01X54353Y-1062417D02*
X52833D01*
G01X57933Y-1060000D02*
Y-1065000D01*
X60467D01*
G01X64300Y-1065167D02*
X64173Y-1065083D01*
Y-1064917D01*
X64300Y-1064833D01*
X64427Y-1064917D01*
Y-1065083D01*
X64300Y-1065167D01*
G01Y-1062917D02*
X64173Y-1062833D01*
Y-1062667D01*
X64300Y-1062583D01*
X64427Y-1062667D01*
Y-1062833D01*
X64300Y-1062917D01*
G01X69083Y-1066667D02*
X68450Y-1065833D01*
X68133Y-1065000D01*
Y-1061667D01*
X68450Y-1060833D01*
X69083Y-1060000D01*
G01X74500D02*
X73993Y-1060167D01*
X73613Y-1060583D01*
X73360Y-1061083D01*
X73170Y-1061750D01*
X73107Y-1062500D01*
X73170Y-1063250D01*
X73360Y-1063917D01*
X73613Y-1064417D01*
X73993Y-1064833D01*
X74500Y-1065000D01*
X75007Y-1064833D01*
X75387Y-1064417D01*
X75640Y-1063917D01*
X75830Y-1063250D01*
X75893Y-1062500D01*
X75830Y-1061750D01*
X75640Y-1061083D01*
X75387Y-1060583D01*
X75007Y-1060167D01*
X74500Y-1060000D01*
G01X78207Y-1064000D02*
X78587Y-1064583D01*
X79093Y-1064917D01*
X79663Y-1065000D01*
X80170Y-1064917D01*
X80677Y-1064500D01*
X80993Y-1064000D01*
X81057Y-1063500D01*
X80930Y-1062917D01*
X80487Y-1062500D01*
X80043Y-1062333D01*
X79473D01*
G01X80043D02*
X80423Y-1062083D01*
X80740Y-1061667D01*
X80867Y-1061167D01*
X80740Y-1060667D01*
X80423Y-1060250D01*
X79853Y-1060000D01*
X79283Y-1060083D01*
X78713Y-1060417D01*
G01X85017Y-1066667D02*
X85650Y-1065833D01*
X85967Y-1065000D01*
Y-1061667D01*
X85650Y-1060833D01*
X85017Y-1060000D01*
G01X88407Y-1064000D02*
X88787Y-1064583D01*
X89293Y-1064917D01*
X89863Y-1065000D01*
X90370Y-1064917D01*
X90877Y-1064500D01*
X91193Y-1064000D01*
X91257Y-1063500D01*
X91130Y-1062917D01*
X90687Y-1062500D01*
X90243Y-1062333D01*
X89673D01*
G01X90243D02*
X90623Y-1062083D01*
X90940Y-1061667D01*
X91067Y-1061167D01*
X90940Y-1060667D01*
X90623Y-1060250D01*
X90053Y-1060000D01*
X89483Y-1060083D01*
X88913Y-1060417D01*
G01X93697Y-1060833D02*
X94077Y-1060333D01*
X94520Y-1060083D01*
X95027Y-1060000D01*
X95660Y-1060167D01*
X96103Y-1060583D01*
X96230Y-1061083D01*
X96167Y-1061583D01*
X95913Y-1062000D01*
X94647Y-1062833D01*
X94077Y-1063417D01*
X93697Y-1064250D01*
X93570Y-1065000D01*
X96230D01*
G01X99873D02*
X100000Y-1063917D01*
X100190Y-1063000D01*
X100443Y-1062167D01*
X100760Y-1061250D01*
X101267Y-1060000D01*
X98733D01*
G01X104277Y-1063333D02*
X105923D01*
G01X108997Y-1060833D02*
X109377Y-1060333D01*
X109820Y-1060083D01*
X110327Y-1060000D01*
X110960Y-1060167D01*
X111403Y-1060583D01*
X111530Y-1061083D01*
X111467Y-1061583D01*
X111213Y-1062000D01*
X109947Y-1062833D01*
X109377Y-1063417D01*
X108997Y-1064250D01*
X108870Y-1065000D01*
X111530D01*
G01X113907Y-1064000D02*
X114287Y-1064583D01*
X114793Y-1064917D01*
X115363Y-1065000D01*
X115870Y-1064917D01*
X116377Y-1064500D01*
X116693Y-1064000D01*
X116757Y-1063500D01*
X116630Y-1062917D01*
X116187Y-1062500D01*
X115743Y-1062333D01*
X115173D01*
G01X115743D02*
X116123Y-1062083D01*
X116440Y-1061667D01*
X116567Y-1061167D01*
X116440Y-1060667D01*
X116123Y-1060250D01*
X115553Y-1060000D01*
X114983Y-1060083D01*
X114413Y-1060417D01*
G01X121160Y-1065000D02*
Y-1060000D01*
X118817Y-1063583D01*
X121983D01*
G01X124107Y-1064250D02*
X124487Y-1064667D01*
X124930Y-1064917D01*
X125500Y-1065000D01*
X126070Y-1064833D01*
X126513Y-1064500D01*
X126830Y-1063917D01*
X126893Y-1063250D01*
X126767Y-1062583D01*
X126450Y-1062167D01*
X126007Y-1061833D01*
X125563Y-1061750D01*
X125120Y-1061833D01*
X124550Y-1062167D01*
X124740Y-1060000D01*
X126450D01*
G01X134497Y-1065000D02*
Y-1060000D01*
X136903D01*
G01X136017Y-1062417D02*
X134497D01*
G01X139217Y-1065000D02*
X140800Y-1060000D01*
X142383Y-1065000D01*
G01X141813Y-1063250D02*
X139787D01*
G01X144570Y-1065000D02*
X147230Y-1060000D01*
G01X144570D02*
X147230Y-1065000D01*
G01X151000Y-1065167D02*
X150873Y-1065083D01*
Y-1064917D01*
X151000Y-1064833D01*
X151127Y-1064917D01*
Y-1065083D01*
X151000Y-1065167D01*
G01Y-1062917D02*
X150873Y-1062833D01*
Y-1062667D01*
X151000Y-1062583D01*
X151127Y-1062667D01*
Y-1062833D01*
X151000Y-1062917D01*
G01X155783Y-1066667D02*
X155150Y-1065833D01*
X154833Y-1065000D01*
Y-1061667D01*
X155150Y-1060833D01*
X155783Y-1060000D01*
G01X161200D02*
X160693Y-1060167D01*
X160313Y-1060583D01*
X160060Y-1061083D01*
X159870Y-1061750D01*
X159807Y-1062500D01*
X159870Y-1063250D01*
X160060Y-1063917D01*
X160313Y-1064417D01*
X160693Y-1064833D01*
X161200Y-1065000D01*
X161707Y-1064833D01*
X162087Y-1064417D01*
X162340Y-1063917D01*
X162530Y-1063250D01*
X162593Y-1062500D01*
X162530Y-1061750D01*
X162340Y-1061083D01*
X162087Y-1060583D01*
X161707Y-1060167D01*
X161200Y-1060000D01*
G01X164907Y-1064000D02*
X165287Y-1064583D01*
X165793Y-1064917D01*
X166363Y-1065000D01*
X166870Y-1064917D01*
X167377Y-1064500D01*
X167693Y-1064000D01*
X167757Y-1063500D01*
X167630Y-1062917D01*
X167187Y-1062500D01*
X166743Y-1062333D01*
X166173D01*
G01X166743D02*
X167123Y-1062083D01*
X167440Y-1061667D01*
X167567Y-1061167D01*
X167440Y-1060667D01*
X167123Y-1060250D01*
X166553Y-1060000D01*
X165983Y-1060083D01*
X165413Y-1060417D01*
G01X171717Y-1066667D02*
X172350Y-1065833D01*
X172667Y-1065000D01*
Y-1061667D01*
X172350Y-1060833D01*
X171717Y-1060000D01*
G01X175107Y-1064000D02*
X175487Y-1064583D01*
X175993Y-1064917D01*
X176563Y-1065000D01*
X177070Y-1064917D01*
X177577Y-1064500D01*
X177893Y-1064000D01*
X177957Y-1063500D01*
X177830Y-1062917D01*
X177387Y-1062500D01*
X176943Y-1062333D01*
X176373D01*
G01X176943D02*
X177323Y-1062083D01*
X177640Y-1061667D01*
X177767Y-1061167D01*
X177640Y-1060667D01*
X177323Y-1060250D01*
X176753Y-1060000D01*
X176183Y-1060083D01*
X175613Y-1060417D01*
G01X180523Y-1064417D02*
X180967Y-1064833D01*
X181473Y-1065000D01*
X181980Y-1064833D01*
X182423Y-1064333D01*
X182740Y-1063583D01*
X182867Y-1062833D01*
Y-1061917D01*
X182740Y-1061167D01*
X182423Y-1060500D01*
X182043Y-1060167D01*
X181600Y-1060000D01*
X181093Y-1060167D01*
X180713Y-1060500D01*
X180460Y-1061000D01*
X180333Y-1061667D01*
X180460Y-1062250D01*
X180777Y-1062833D01*
X181157Y-1063167D01*
X181600Y-1063250D01*
X182107Y-1063083D01*
X182487Y-1062667D01*
X182867Y-1061917D01*
G01X186573Y-1065000D02*
X186700Y-1063917D01*
X186890Y-1063000D01*
X187143Y-1062167D01*
X187460Y-1061250D01*
X187967Y-1060000D01*
X185433D01*
G01X190977Y-1063333D02*
X192623D01*
G01X195507Y-1064000D02*
X195887Y-1064583D01*
X196393Y-1064917D01*
X196963Y-1065000D01*
X197470Y-1064917D01*
X197977Y-1064500D01*
X198293Y-1064000D01*
X198357Y-1063500D01*
X198230Y-1062917D01*
X197787Y-1062500D01*
X197343Y-1062333D01*
X196773D01*
G01X197343D02*
X197723Y-1062083D01*
X198040Y-1061667D01*
X198167Y-1061167D01*
X198040Y-1060667D01*
X197723Y-1060250D01*
X197153Y-1060000D01*
X196583Y-1060083D01*
X196013Y-1060417D01*
G01X200797Y-1062917D02*
X201240Y-1062333D01*
X201620Y-1062000D01*
X202127Y-1061833D01*
X202570Y-1062000D01*
X202887Y-1062333D01*
X203140Y-1062833D01*
X203203Y-1063417D01*
X203140Y-1063917D01*
X202887Y-1064417D01*
X202507Y-1064833D01*
X202063Y-1065000D01*
X201557Y-1064833D01*
X201113Y-1064333D01*
X200860Y-1063583D01*
X200797Y-1062750D01*
X200923Y-1061667D01*
X201113Y-1061083D01*
X201430Y-1060500D01*
X201873Y-1060083D01*
X202317Y-1060000D01*
X202760Y-1060167D01*
X203077Y-1060583D01*
G01X207100Y-1065000D02*
Y-1060000D01*
X206340Y-1061000D01*
G01Y-1065000D02*
X207860D01*
G01X212960D02*
Y-1060000D01*
X210617Y-1063583D01*
X213783D01*
G01X232000Y-995000D02*
Y-1070000D01*
G01Y-1045000D02*
X335000D01*
Y-1020000D01*
G01X232000D02*
X335000D01*
G01X337000Y-995000D02*
Y-1070000D01*
G01X335000Y-995000D02*
Y-1070000D01*
G01X342507Y-1055000D02*
Y-1050000D01*
X343773D01*
X344280Y-1050250D01*
X344660Y-1050583D01*
X344977Y-1051083D01*
X345230Y-1051667D01*
X345293Y-1052500D01*
X345230Y-1053333D01*
X344977Y-1053917D01*
X344660Y-1054417D01*
X344280Y-1054750D01*
X343773Y-1055000D01*
X342507D01*
G01X347417D02*
X349000Y-1050000D01*
X350583Y-1055000D01*
G01X350013Y-1053250D02*
X347987D01*
G01X354100Y-1050000D02*
Y-1055000D01*
G01X352643Y-1050000D02*
X355557D01*
G01X360467Y-1055000D02*
X357933D01*
Y-1050000D01*
X360467D01*
G01X359453Y-1052417D02*
X357933D01*
G01X364300Y-1055167D02*
X364173Y-1055083D01*
Y-1054917D01*
X364300Y-1054833D01*
X364427Y-1054917D01*
Y-1055083D01*
X364300Y-1055167D01*
G01Y-1052917D02*
X364173Y-1052833D01*
Y-1052667D01*
X364300Y-1052583D01*
X364427Y-1052667D01*
Y-1052833D01*
X364300Y-1052917D01*
G01X337000Y-1045000D02*
X537000D01*
G01X342633Y-1030000D02*
Y-1025000D01*
X344153D01*
X344660Y-1025250D01*
X345040Y-1025833D01*
X345167Y-1026500D01*
X345040Y-1027167D01*
X344723Y-1027667D01*
X344153Y-1027917D01*
X342633D01*
G01X347860Y-1030167D02*
X350140Y-1025000D01*
G01X352643Y-1030000D02*
Y-1025000D01*
X355557Y-1030000D01*
Y-1025000D01*
G01X359200Y-1030167D02*
X359073Y-1030083D01*
Y-1029917D01*
X359200Y-1029833D01*
X359327Y-1029917D01*
Y-1030083D01*
X359200Y-1030167D01*
G01Y-1027917D02*
X359073Y-1027833D01*
Y-1027667D01*
X359200Y-1027583D01*
X359327Y-1027667D01*
Y-1027833D01*
X359200Y-1027917D01*
G01X342633Y-1005000D02*
Y-1000000D01*
X344153D01*
X344660Y-1000250D01*
X345040Y-1000833D01*
X345167Y-1001500D01*
X345040Y-1002167D01*
X344723Y-1002667D01*
X344153Y-1002917D01*
X342633D01*
G01X347733Y-1005000D02*
Y-1000000D01*
X349317D01*
X349823Y-1000250D01*
X350140Y-1000583D01*
X350267Y-1001250D01*
X350140Y-1001917D01*
X349760Y-1002333D01*
X349317Y-1002583D01*
X347733D01*
G01X349317D02*
X350267Y-1005000D01*
G01X354100D02*
X353593Y-1004917D01*
X353150Y-1004583D01*
X352770Y-1004083D01*
X352517Y-1003500D01*
X352390Y-1002833D01*
Y-1002167D01*
X352517Y-1001500D01*
X352770Y-1000917D01*
X353150Y-1000417D01*
X353593Y-1000083D01*
X354100Y-1000000D01*
X354607Y-1000083D01*
X355050Y-1000417D01*
X355430Y-1000917D01*
X355683Y-1001500D01*
X355810Y-1002167D01*
Y-1002833D01*
X355683Y-1003500D01*
X355430Y-1004083D01*
X355050Y-1004583D01*
X354607Y-1004917D01*
X354100Y-1005000D01*
G01X357933Y-1004000D02*
X358250Y-1004500D01*
X358630Y-1004833D01*
X359073Y-1005000D01*
X359580Y-1004833D01*
X359960Y-1004500D01*
X360340Y-1004000D01*
X360467Y-1003333D01*
Y-1000000D01*
G01X365567Y-1005000D02*
X363033D01*
Y-1000000D01*
X365567D01*
G01X364553Y-1002417D02*
X363033D01*
G01X370793Y-1000417D02*
X370413Y-1000167D01*
X369970Y-1000000D01*
X369463D01*
X368893Y-1000250D01*
X368450Y-1000667D01*
X368133Y-1001167D01*
X367880Y-1002000D01*
X367817Y-1002750D01*
X367943Y-1003500D01*
X368133Y-1004000D01*
X368513Y-1004500D01*
X368957Y-1004833D01*
X369400Y-1005000D01*
X369843D01*
X370287Y-1004833D01*
X370667Y-1004583D01*
X370983Y-1004250D01*
G01X374500Y-1000000D02*
Y-1005000D01*
G01X373043Y-1000000D02*
X375957D01*
G01X379600Y-1005167D02*
X379473Y-1005083D01*
Y-1004917D01*
X379600Y-1004833D01*
X379727Y-1004917D01*
Y-1005083D01*
X379600Y-1005167D01*
G01Y-1002917D02*
X379473Y-1002833D01*
Y-1002667D01*
X379600Y-1002583D01*
X379727Y-1002667D01*
Y-1002833D01*
X379600Y-1002917D01*
G01X337000Y-1020000D02*
X537000D01*
G01X452000Y-1045000D02*
Y-1070000D01*
G01X454633Y-1047500D02*
Y-1052500D01*
X457167D01*
G01X460240Y-1047500D02*
X461760D01*
G01X461000D02*
Y-1052500D01*
G01X460240D02*
X461760D01*
G01X466607Y-1049833D02*
X466860Y-1049583D01*
X467050Y-1049167D01*
X467177Y-1048583D01*
X467050Y-1048083D01*
X466797Y-1047750D01*
X466353Y-1047500D01*
X464643D01*
Y-1052500D01*
X466733D01*
X467177Y-1052167D01*
X467430Y-1051667D01*
X467557Y-1051083D01*
X467430Y-1050500D01*
X467050Y-1050000D01*
X466607Y-1049833D01*
X464643D01*
G01X471200Y-1052667D02*
X471073Y-1052583D01*
Y-1052417D01*
X471200Y-1052333D01*
X471327Y-1052417D01*
Y-1052583D01*
X471200Y-1052667D01*
G01Y-1050417D02*
X471073Y-1050333D01*
Y-1050167D01*
X471200Y-1050083D01*
X471327Y-1050167D01*
Y-1050333D01*
X471200Y-1050417D01*
G01X495000Y-1045000D02*
Y-1070000D01*
G01X498900Y-1047500D02*
Y-1052500D01*
G01X497443Y-1047500D02*
X500357D01*
G01X504000Y-1052500D02*
X503620Y-1052417D01*
X503240Y-1052083D01*
X502987Y-1051500D01*
X502860Y-1050833D01*
X502987Y-1050167D01*
X503240Y-1049583D01*
X503620Y-1049250D01*
X504000Y-1049167D01*
X504380Y-1049250D01*
X504760Y-1049583D01*
X505013Y-1050167D01*
X505077Y-1050833D01*
X505013Y-1051500D01*
X504760Y-1052083D01*
X504380Y-1052417D01*
X504000Y-1052500D01*
G01X509100D02*
X508720Y-1052417D01*
X508340Y-1052083D01*
X508087Y-1051500D01*
X507960Y-1050833D01*
X508087Y-1050167D01*
X508340Y-1049583D01*
X508720Y-1049250D01*
X509100Y-1049167D01*
X509480Y-1049250D01*
X509860Y-1049583D01*
X510113Y-1050167D01*
X510177Y-1050833D01*
X510113Y-1051500D01*
X509860Y-1052083D01*
X509480Y-1052417D01*
X509100Y-1052500D01*
G01X514200D02*
Y-1047500D01*
G01X519300Y-1052667D02*
X519173Y-1052583D01*
Y-1052417D01*
X519300Y-1052333D01*
X519427Y-1052417D01*
Y-1052583D01*
X519300Y-1052667D01*
G01Y-1050417D02*
X519173Y-1050333D01*
Y-1050167D01*
X519300Y-1050083D01*
X519427Y-1050167D01*
Y-1050333D01*
X519300Y-1050417D01*
G01X495000Y-1020000D02*
Y-1045000D01*
G01X497633Y-1027500D02*
Y-1022500D01*
X499217D01*
X499723Y-1022750D01*
X500040Y-1023083D01*
X500167Y-1023750D01*
X500040Y-1024417D01*
X499660Y-1024833D01*
X499217Y-1025083D01*
X497633D01*
G01X499217D02*
X500167Y-1027500D01*
G01X505267D02*
X502733D01*
Y-1022500D01*
X505267D01*
G01X504253Y-1024917D02*
X502733D01*
G01X507517Y-1022500D02*
X509100Y-1027500D01*
X510683Y-1022500D01*
G01X514200Y-1027667D02*
X514073Y-1027583D01*
Y-1027417D01*
X514200Y-1027333D01*
X514327Y-1027417D01*
Y-1027583D01*
X514200Y-1027667D01*
G01Y-1025417D02*
X514073Y-1025333D01*
Y-1025167D01*
X514200Y-1025083D01*
X514327Y-1025167D01*
Y-1025333D01*
X514200Y-1025417D01*
G01X503013Y-1073167D02*
X503120Y-1073042D01*
X503200Y-1072833D01*
X503253Y-1072542D01*
X503200Y-1072292D01*
X503093Y-1072125D01*
X502907Y-1072000D01*
X502187D01*
Y-1074500D01*
X503067D01*
X503253Y-1074333D01*
X503360Y-1074083D01*
X503413Y-1073792D01*
X503360Y-1073500D01*
X503200Y-1073250D01*
X503013Y-1073167D01*
X502187D01*
G01X505480Y-1074500D02*
Y-1072833D01*
G01Y-1073125D02*
X505373Y-1072958D01*
X505213Y-1072875D01*
X505027Y-1072833D01*
X504840Y-1072917D01*
X504680Y-1073083D01*
X504573Y-1073333D01*
X504520Y-1073667D01*
X504573Y-1074000D01*
X504680Y-1074250D01*
X504840Y-1074417D01*
X505027Y-1074500D01*
X505213Y-1074458D01*
X505373Y-1074333D01*
X505480Y-1074167D01*
G01X506800Y-1074208D02*
X506933Y-1074375D01*
X507120Y-1074500D01*
X507280D01*
X507440Y-1074417D01*
X507547Y-1074292D01*
X507600Y-1074125D01*
X507573Y-1073875D01*
X507467Y-1073750D01*
X506987Y-1073500D01*
X506880Y-1073208D01*
X506933Y-1073000D01*
X507040Y-1072875D01*
X507200Y-1072833D01*
X507360Y-1072875D01*
X507520Y-1073000D01*
G01X509000Y-1073375D02*
X509853D01*
X509773Y-1073083D01*
X509640Y-1072917D01*
X509453Y-1072833D01*
X509267Y-1072875D01*
X509107Y-1073000D01*
X509000Y-1073292D01*
X508947Y-1073542D01*
Y-1073792D01*
X509000Y-1074042D01*
X509133Y-1074292D01*
X509293Y-1074458D01*
X509480Y-1074500D01*
X509667Y-1074417D01*
X509853Y-1074167D01*
G01X511120Y-1074500D02*
Y-1072000D01*
G01Y-1073250D02*
X511253Y-1073000D01*
X511413Y-1072875D01*
X511573Y-1072833D01*
X511813Y-1072917D01*
X511973Y-1073083D01*
X512080Y-1073375D01*
Y-1073708D01*
X512027Y-1074042D01*
X511920Y-1074292D01*
X511733Y-1074458D01*
X511573Y-1074500D01*
X511413Y-1074458D01*
X511253Y-1074333D01*
X511120Y-1074125D01*
G01X513800Y-1074500D02*
X513640Y-1074458D01*
X513480Y-1074292D01*
X513373Y-1074000D01*
X513320Y-1073667D01*
X513373Y-1073333D01*
X513480Y-1073042D01*
X513640Y-1072875D01*
X513800Y-1072833D01*
X513960Y-1072875D01*
X514120Y-1073042D01*
X514227Y-1073333D01*
X514253Y-1073667D01*
X514227Y-1074000D01*
X514120Y-1074292D01*
X513960Y-1074458D01*
X513800Y-1074500D01*
G01X516480D02*
Y-1072833D01*
G01Y-1073125D02*
X516373Y-1072958D01*
X516213Y-1072875D01*
X516027Y-1072833D01*
X515840Y-1072917D01*
X515680Y-1073083D01*
X515573Y-1073333D01*
X515520Y-1073667D01*
X515573Y-1074000D01*
X515680Y-1074250D01*
X515840Y-1074417D01*
X516027Y-1074500D01*
X516213Y-1074458D01*
X516373Y-1074333D01*
X516480Y-1074167D01*
G01X517827Y-1074500D02*
Y-1072833D01*
G01Y-1073167D02*
X517960Y-1073000D01*
X518093Y-1072875D01*
X518280Y-1072833D01*
X518413Y-1072875D01*
X518573Y-1073000D01*
G01X520880Y-1072000D02*
Y-1074500D01*
G01Y-1074125D02*
X520773Y-1074333D01*
X520613Y-1074458D01*
X520427Y-1074500D01*
X520213Y-1074417D01*
X520053Y-1074208D01*
X519947Y-1073958D01*
X519920Y-1073667D01*
X519947Y-1073375D01*
X520053Y-1073125D01*
X520213Y-1072917D01*
X520427Y-1072833D01*
X520613Y-1072875D01*
X520747Y-1072958D01*
X520880Y-1073125D01*
G01X524267Y-1074500D02*
Y-1072000D01*
X524933D01*
X525147Y-1072125D01*
X525280Y-1072292D01*
X525333Y-1072625D01*
X525280Y-1072958D01*
X525120Y-1073167D01*
X524933Y-1073292D01*
X524267D01*
G01X524933D02*
X525333Y-1074500D01*
G01X526600Y-1073375D02*
X527453D01*
X527373Y-1073083D01*
X527240Y-1072917D01*
X527053Y-1072833D01*
X526867Y-1072875D01*
X526707Y-1073000D01*
X526600Y-1073292D01*
X526547Y-1073542D01*
Y-1073792D01*
X526600Y-1074042D01*
X526733Y-1074292D01*
X526893Y-1074458D01*
X527080Y-1074500D01*
X527267Y-1074417D01*
X527453Y-1074167D01*
G01X528720Y-1072833D02*
X529200Y-1074500D01*
X529680Y-1072833D01*
G01X531400Y-1074583D02*
X531347Y-1074542D01*
Y-1074458D01*
X531400Y-1074417D01*
X531453Y-1074458D01*
Y-1074542D01*
X531400Y-1074583D01*
G01X533600Y-1074500D02*
X533787Y-1074458D01*
X534000Y-1074333D01*
X534133Y-1074125D01*
X534187Y-1073833D01*
X534133Y-1073542D01*
X533973Y-1073292D01*
X533733Y-1073167D01*
X533467D01*
X533307Y-1073083D01*
X533173Y-1072875D01*
X533120Y-1072583D01*
X533200Y-1072292D01*
X533387Y-1072083D01*
X533600Y-1072000D01*
X533813Y-1072083D01*
X534000Y-1072292D01*
X534080Y-1072583D01*
X534027Y-1072875D01*
X533893Y-1073083D01*
X533733Y-1073167D01*
X533467D01*
X533227Y-1073292D01*
X533067Y-1073542D01*
X533013Y-1073833D01*
X533067Y-1074125D01*
X533200Y-1074333D01*
X533413Y-1074458D01*
X533600Y-1074500D01*
G01X536013Y-1073167D02*
X536120Y-1073042D01*
X536200Y-1072833D01*
X536253Y-1072542D01*
X536200Y-1072292D01*
X536093Y-1072125D01*
X535907Y-1072000D01*
X535187D01*
Y-1074500D01*
X536067D01*
X536253Y-1074333D01*
X536360Y-1074083D01*
X536413Y-1073792D01*
X536360Y-1073500D01*
X536200Y-1073250D01*
X536013Y-1073167D01*
X535187D01*
G01X-457143Y-1211429D02*
Y2242857D01*
X4308572D01*
Y-1211429D01*
X-457143D01*
G01X71650Y-1024800D02*
X69130Y-1024383D01*
X66925Y-1022717D01*
X65035Y-1020217D01*
X63775Y-1017300D01*
X63145Y-1013967D01*
Y-1010633D01*
X63775Y-1007300D01*
X65035Y-1004383D01*
X66925Y-1001884D01*
X69130Y-1000217D01*
X71650Y-999800D01*
X74170Y-1000217D01*
X76375Y-1001884D01*
X78265Y-1004383D01*
X79525Y-1007300D01*
X80155Y-1010633D01*
Y-1013967D01*
X79525Y-1017300D01*
X78265Y-1020217D01*
X76375Y-1022717D01*
X74170Y-1024383D01*
X71650Y-1024800D01*
G01X74170Y-1018133D02*
X77950Y-1024800D01*
G01X91495Y-1008134D02*
Y-1019800D01*
X92755Y-1022717D01*
X94645Y-1024383D01*
X96850Y-1024800D01*
X99055Y-1024383D01*
X100945Y-1022717D01*
X102205Y-1019800D01*
G01Y-1024800D02*
Y-1008134D01*
G01X127720Y-1024800D02*
Y-1008134D01*
G01Y-1011050D02*
X126460Y-1009384D01*
X124570Y-1008550D01*
X122365Y-1008134D01*
X120160Y-1008967D01*
X118270Y-1010633D01*
X117010Y-1013134D01*
X116380Y-1016467D01*
X117010Y-1019800D01*
X118270Y-1022301D01*
X120160Y-1023967D01*
X122365Y-1024800D01*
X124570Y-1024383D01*
X126460Y-1023134D01*
X127720Y-1021467D01*
G01X141895Y-1024800D02*
Y-1008134D01*
G01Y-1012300D02*
X143155Y-1010217D01*
X145045Y-1008550D01*
X147565Y-1008134D01*
X149770Y-1008550D01*
X151660Y-1010217D01*
X152605Y-1013134D01*
Y-1024800D01*
G01X172450Y-999800D02*
Y-1024800D01*
G01X168040Y-1008134D02*
X176860D01*
G01X203320Y-1024800D02*
Y-1008134D01*
G01Y-1011050D02*
X202060Y-1009384D01*
X200170Y-1008550D01*
X197965Y-1008134D01*
X195760Y-1008967D01*
X193870Y-1010633D01*
X192610Y-1013134D01*
X191980Y-1016467D01*
X192610Y-1019800D01*
X193870Y-1022301D01*
X195760Y-1023967D01*
X197965Y-1024800D01*
X200170Y-1024383D01*
X202060Y-1023134D01*
X203320Y-1021467D01*
G01X49820Y-1042350D02*
X51387D01*
Y-1044240D01*
X50917Y-1044870D01*
X50368Y-1045290D01*
X49585Y-1045500D01*
X48802Y-1045290D01*
X48253Y-1044870D01*
X47783Y-1044240D01*
X47470Y-1043505D01*
X47313Y-1042665D01*
Y-1041930D01*
X47470Y-1041300D01*
X47783Y-1040565D01*
X48253Y-1039935D01*
X48723Y-1039515D01*
X49350Y-1039200D01*
X49898D01*
X50525Y-1039410D01*
X50995Y-1039830D01*
G01X53927Y-1039200D02*
Y-1043715D01*
X54240Y-1044660D01*
X54867Y-1045290D01*
X55650Y-1045500D01*
X56433Y-1045290D01*
X57060Y-1044660D01*
X57373Y-1043715D01*
Y-1039200D01*
G01X61010D02*
X62890D01*
G01X61950D02*
Y-1045500D01*
G01X61010D02*
X62890D01*
G01X66605Y-1044660D02*
X67232Y-1045185D01*
X67937Y-1045500D01*
X68563D01*
X69190Y-1045185D01*
X69660Y-1044660D01*
X69895Y-1043925D01*
X69738Y-1043190D01*
X69347Y-1042560D01*
X68642Y-1042140D01*
X67702Y-1041930D01*
X67153Y-1041510D01*
X66918Y-1040775D01*
X67075Y-1040040D01*
X67467Y-1039515D01*
X68015Y-1039200D01*
X68563D01*
X69112Y-1039410D01*
X69582Y-1039935D01*
G01X72905Y-1045500D02*
Y-1039200D01*
G01X76195D02*
Y-1045500D01*
G01Y-1042350D02*
X72905D01*
G01X78892Y-1045500D02*
X80850Y-1039200D01*
X82808Y-1045500D01*
G01X82103Y-1043295D02*
X79597D01*
G01X85348Y-1045500D02*
Y-1039200D01*
X88952Y-1045500D01*
Y-1039200D01*
G01X98027Y-1045500D02*
Y-1039200D01*
X99593D01*
X100220Y-1039515D01*
X100690Y-1039935D01*
X101082Y-1040565D01*
X101395Y-1041300D01*
X101473Y-1042350D01*
X101395Y-1043400D01*
X101082Y-1044135D01*
X100690Y-1044765D01*
X100220Y-1045185D01*
X99593Y-1045500D01*
X98027D01*
G01X105110Y-1039200D02*
X106990D01*
G01X106050D02*
Y-1045500D01*
G01X105110D02*
X106990D01*
G01X110705Y-1044660D02*
X111332Y-1045185D01*
X112037Y-1045500D01*
X112663D01*
X113290Y-1045185D01*
X113760Y-1044660D01*
X113995Y-1043925D01*
X113838Y-1043190D01*
X113447Y-1042560D01*
X112742Y-1042140D01*
X111802Y-1041930D01*
X111253Y-1041510D01*
X111018Y-1040775D01*
X111175Y-1040040D01*
X111567Y-1039515D01*
X112115Y-1039200D01*
X112663D01*
X113212Y-1039410D01*
X113682Y-1039935D01*
G01X118650Y-1039200D02*
Y-1045500D01*
G01X116848Y-1039200D02*
X120452D01*
G01X124950Y-1045710D02*
X124793Y-1045605D01*
Y-1045395D01*
X124950Y-1045290D01*
X125107Y-1045395D01*
Y-1045605D01*
X124950Y-1045710D01*
G01X131093Y-1046655D02*
X131407Y-1045290D01*
G01X137550Y-1039200D02*
Y-1045500D01*
G01X135748Y-1039200D02*
X139352D01*
G01X141892Y-1045500D02*
X143850Y-1039200D01*
X145808Y-1045500D01*
G01X145103Y-1043295D02*
X142597D01*
G01X150150Y-1045500D02*
X149523Y-1045395D01*
X148975Y-1044975D01*
X148505Y-1044345D01*
X148192Y-1043610D01*
X148035Y-1042770D01*
Y-1041930D01*
X148192Y-1041090D01*
X148505Y-1040355D01*
X148975Y-1039725D01*
X149523Y-1039305D01*
X150150Y-1039200D01*
X150777Y-1039305D01*
X151325Y-1039725D01*
X151795Y-1040355D01*
X152108Y-1041090D01*
X152265Y-1041930D01*
Y-1042770D01*
X152108Y-1043610D01*
X151795Y-1044345D01*
X151325Y-1044975D01*
X150777Y-1045395D01*
X150150Y-1045500D01*
G01X156450D02*
Y-1042665D01*
X154883Y-1039200D01*
G01X158017D02*
X156450Y-1042665D01*
G01X161027Y-1039200D02*
Y-1043715D01*
X161340Y-1044660D01*
X161967Y-1045290D01*
X162750Y-1045500D01*
X163533Y-1045290D01*
X164160Y-1044660D01*
X164473Y-1043715D01*
Y-1039200D01*
G01X167092Y-1045500D02*
X169050Y-1039200D01*
X171008Y-1045500D01*
G01X170303Y-1043295D02*
X167797D01*
G01X173548Y-1045500D02*
Y-1039200D01*
X177152Y-1045500D01*
Y-1039200D01*
G01X51073Y-1049725D02*
X50603Y-1049410D01*
X50055Y-1049200D01*
X49428D01*
X48723Y-1049515D01*
X48175Y-1050040D01*
X47783Y-1050670D01*
X47470Y-1051720D01*
X47392Y-1052665D01*
X47548Y-1053610D01*
X47783Y-1054240D01*
X48253Y-1054870D01*
X48802Y-1055290D01*
X49350Y-1055500D01*
X49898D01*
X50447Y-1055290D01*
X50917Y-1054975D01*
X51308Y-1054555D01*
G01X54710Y-1049200D02*
X56590D01*
G01X55650D02*
Y-1055500D01*
G01X54710D02*
X56590D01*
G01X61950Y-1049200D02*
Y-1055500D01*
G01X60148Y-1049200D02*
X63752D01*
G01X68250Y-1055500D02*
Y-1052665D01*
X66683Y-1049200D01*
G01X69817D02*
X68250Y-1052665D01*
G01X79127Y-1054240D02*
X79597Y-1054975D01*
X80223Y-1055395D01*
X80928Y-1055500D01*
X81555Y-1055395D01*
X82182Y-1054870D01*
X82573Y-1054240D01*
X82652Y-1053610D01*
X82495Y-1052875D01*
X81947Y-1052350D01*
X81398Y-1052140D01*
X80693D01*
G01X81398D02*
X81868Y-1051825D01*
X82260Y-1051300D01*
X82417Y-1050670D01*
X82260Y-1050040D01*
X81868Y-1049515D01*
X81163Y-1049200D01*
X80458Y-1049305D01*
X79753Y-1049725D01*
G01X85427Y-1054240D02*
X85897Y-1054975D01*
X86523Y-1055395D01*
X87228Y-1055500D01*
X87855Y-1055395D01*
X88482Y-1054870D01*
X88873Y-1054240D01*
X88952Y-1053610D01*
X88795Y-1052875D01*
X88247Y-1052350D01*
X87698Y-1052140D01*
X86993D01*
G01X87698D02*
X88168Y-1051825D01*
X88560Y-1051300D01*
X88717Y-1050670D01*
X88560Y-1050040D01*
X88168Y-1049515D01*
X87463Y-1049200D01*
X86758Y-1049305D01*
X86053Y-1049725D01*
G01X91727Y-1054240D02*
X92197Y-1054975D01*
X92823Y-1055395D01*
X93528Y-1055500D01*
X94155Y-1055395D01*
X94782Y-1054870D01*
X95173Y-1054240D01*
X95252Y-1053610D01*
X95095Y-1052875D01*
X94547Y-1052350D01*
X93998Y-1052140D01*
X93293D01*
G01X93998D02*
X94468Y-1051825D01*
X94860Y-1051300D01*
X95017Y-1050670D01*
X94860Y-1050040D01*
X94468Y-1049515D01*
X93763Y-1049200D01*
X93058Y-1049305D01*
X92353Y-1049725D01*
G01X99593Y-1055500D02*
X99750Y-1054135D01*
X99985Y-1052980D01*
X100298Y-1051930D01*
X100690Y-1050775D01*
X101317Y-1049200D01*
X98183D01*
G01X105893Y-1055500D02*
X106050Y-1054135D01*
X106285Y-1052980D01*
X106598Y-1051930D01*
X106990Y-1050775D01*
X107617Y-1049200D01*
X104483D01*
G01X112193Y-1056655D02*
X112507Y-1055290D01*
G01X118650Y-1049200D02*
Y-1055500D01*
G01X116848Y-1049200D02*
X120452D01*
G01X122992Y-1055500D02*
X124950Y-1049200D01*
X126908Y-1055500D01*
G01X126203Y-1053295D02*
X123697D01*
G01X130310Y-1049200D02*
X132190D01*
G01X131250D02*
Y-1055500D01*
G01X130310D02*
X132190D01*
G01X135200Y-1049200D02*
X136297Y-1055500D01*
X137550Y-1049200D01*
X138803Y-1055500D01*
X139900Y-1049200D01*
G01X141892Y-1055500D02*
X143850Y-1049200D01*
X145808Y-1055500D01*
G01X145103Y-1053295D02*
X142597D01*
G01X148348Y-1055500D02*
Y-1049200D01*
X151952Y-1055500D01*
Y-1049200D01*
G01X162358Y-1057600D02*
X161575Y-1056550D01*
X161183Y-1055500D01*
Y-1051300D01*
X161575Y-1050250D01*
X162358Y-1049200D01*
G01X173783Y-1055500D02*
Y-1049200D01*
X175742D01*
X176368Y-1049515D01*
X176760Y-1049935D01*
X176917Y-1050775D01*
X176760Y-1051615D01*
X176290Y-1052140D01*
X175742Y-1052455D01*
X173783D01*
G01X175742D02*
X176917Y-1055500D01*
G01X181650Y-1055710D02*
X181493Y-1055605D01*
Y-1055395D01*
X181650Y-1055290D01*
X181807Y-1055395D01*
Y-1055605D01*
X181650Y-1055710D01*
G01X187950Y-1055500D02*
X187323Y-1055395D01*
X186775Y-1054975D01*
X186305Y-1054345D01*
X185992Y-1053610D01*
X185835Y-1052770D01*
Y-1051930D01*
X185992Y-1051090D01*
X186305Y-1050355D01*
X186775Y-1049725D01*
X187323Y-1049305D01*
X187950Y-1049200D01*
X188577Y-1049305D01*
X189125Y-1049725D01*
X189595Y-1050355D01*
X189908Y-1051090D01*
X190065Y-1051930D01*
Y-1052770D01*
X189908Y-1053610D01*
X189595Y-1054345D01*
X189125Y-1054975D01*
X188577Y-1055395D01*
X187950Y-1055500D01*
G01X194250Y-1055710D02*
X194093Y-1055605D01*
Y-1055395D01*
X194250Y-1055290D01*
X194407Y-1055395D01*
Y-1055605D01*
X194250Y-1055710D01*
G01X202273Y-1049725D02*
X201803Y-1049410D01*
X201255Y-1049200D01*
X200628D01*
X199923Y-1049515D01*
X199375Y-1050040D01*
X198983Y-1050670D01*
X198670Y-1051720D01*
X198592Y-1052665D01*
X198748Y-1053610D01*
X198983Y-1054240D01*
X199453Y-1054870D01*
X200002Y-1055290D01*
X200550Y-1055500D01*
X201098D01*
X201647Y-1055290D01*
X202117Y-1054975D01*
X202508Y-1054555D01*
G01X206850Y-1055710D02*
X206693Y-1055605D01*
Y-1055395D01*
X206850Y-1055290D01*
X207007Y-1055395D01*
Y-1055605D01*
X206850Y-1055710D01*
G01X213542Y-1057600D02*
X214325Y-1056550D01*
X214717Y-1055500D01*
Y-1051300D01*
X214325Y-1050250D01*
X213542Y-1049200D01*
G01X47548Y-1035500D02*
Y-1029200D01*
X51152Y-1035500D01*
Y-1029200D01*
G01X55650Y-1035500D02*
X55023Y-1035395D01*
X54475Y-1034975D01*
X54005Y-1034345D01*
X53692Y-1033610D01*
X53535Y-1032770D01*
Y-1031930D01*
X53692Y-1031090D01*
X54005Y-1030355D01*
X54475Y-1029725D01*
X55023Y-1029305D01*
X55650Y-1029200D01*
X56277Y-1029305D01*
X56825Y-1029725D01*
X57295Y-1030355D01*
X57608Y-1031090D01*
X57765Y-1031930D01*
Y-1032770D01*
X57608Y-1033610D01*
X57295Y-1034345D01*
X56825Y-1034975D01*
X56277Y-1035395D01*
X55650Y-1035500D01*
G01X61950Y-1035710D02*
X61793Y-1035605D01*
Y-1035395D01*
X61950Y-1035290D01*
X62107Y-1035395D01*
Y-1035605D01*
X61950Y-1035710D01*
G01X66762Y-1030250D02*
X67232Y-1029620D01*
X67780Y-1029305D01*
X68407Y-1029200D01*
X69190Y-1029410D01*
X69738Y-1029935D01*
X69895Y-1030565D01*
X69817Y-1031195D01*
X69503Y-1031720D01*
X67937Y-1032770D01*
X67232Y-1033505D01*
X66762Y-1034555D01*
X66605Y-1035500D01*
X69895D01*
G01X74550D02*
Y-1029200D01*
X73610Y-1030460D01*
G01Y-1035500D02*
X75490D01*
G01X80850D02*
Y-1029200D01*
X79910Y-1030460D01*
G01Y-1035500D02*
X81790D01*
G01X86993Y-1036655D02*
X87307Y-1035290D01*
G01X91100Y-1029200D02*
X92197Y-1035500D01*
X93450Y-1029200D01*
X94703Y-1035500D01*
X95800Y-1029200D01*
G01X101317Y-1035500D02*
X98183D01*
Y-1029200D01*
X101317D01*
G01X100063Y-1032245D02*
X98183D01*
G01X104248Y-1035500D02*
Y-1029200D01*
X107852Y-1035500D01*
Y-1029200D01*
G01X110705Y-1035500D02*
Y-1029200D01*
G01X113995D02*
Y-1035500D01*
G01Y-1032350D02*
X110705D01*
G01X116927Y-1029200D02*
Y-1033715D01*
X117240Y-1034660D01*
X117867Y-1035290D01*
X118650Y-1035500D01*
X119433Y-1035290D01*
X120060Y-1034660D01*
X120373Y-1033715D01*
Y-1029200D01*
G01X122992Y-1035500D02*
X124950Y-1029200D01*
X126908Y-1035500D01*
G01X126203Y-1033295D02*
X123697D01*
G01X136062Y-1030250D02*
X136532Y-1029620D01*
X137080Y-1029305D01*
X137707Y-1029200D01*
X138490Y-1029410D01*
X139038Y-1029935D01*
X139195Y-1030565D01*
X139117Y-1031195D01*
X138803Y-1031720D01*
X137237Y-1032770D01*
X136532Y-1033505D01*
X136062Y-1034555D01*
X135905Y-1035500D01*
X139195D01*
G01X142048D02*
Y-1029200D01*
X145652Y-1035500D01*
Y-1029200D01*
G01X148427Y-1035500D02*
Y-1029200D01*
X149993D01*
X150620Y-1029515D01*
X151090Y-1029935D01*
X151482Y-1030565D01*
X151795Y-1031300D01*
X151873Y-1032350D01*
X151795Y-1033400D01*
X151482Y-1034135D01*
X151090Y-1034765D01*
X150620Y-1035185D01*
X149993Y-1035500D01*
X148427D01*
G01X161183D02*
Y-1029200D01*
X163142D01*
X163768Y-1029515D01*
X164160Y-1029935D01*
X164317Y-1030775D01*
X164160Y-1031615D01*
X163690Y-1032140D01*
X163142Y-1032455D01*
X161183D01*
G01X163142D02*
X164317Y-1035500D01*
G01X167327D02*
Y-1029200D01*
X168893D01*
X169520Y-1029515D01*
X169990Y-1029935D01*
X170382Y-1030565D01*
X170695Y-1031300D01*
X170773Y-1032350D01*
X170695Y-1033400D01*
X170382Y-1034135D01*
X169990Y-1034765D01*
X169520Y-1035185D01*
X168893Y-1035500D01*
X167327D01*
G01X175350Y-1035710D02*
X175193Y-1035605D01*
Y-1035395D01*
X175350Y-1035290D01*
X175507Y-1035395D01*
Y-1035605D01*
X175350Y-1035710D01*
G01X254500Y-1037500D02*
Y-1029500D01*
X256900D01*
X257700Y-1029900D01*
X258300Y-1030833D01*
X258500Y-1031900D01*
X258300Y-1032967D01*
X257800Y-1033767D01*
X256900Y-1034167D01*
X254500D01*
G01X262000Y-1037500D02*
X264500Y-1029500D01*
X267000Y-1037500D01*
G01X266100Y-1034700D02*
X262900D01*
G01X270400Y-1036434D02*
X271200Y-1037100D01*
X272100Y-1037500D01*
X272900D01*
X273700Y-1037100D01*
X274300Y-1036434D01*
X274600Y-1035500D01*
X274400Y-1034567D01*
X273900Y-1033767D01*
X273000Y-1033233D01*
X271800Y-1032967D01*
X271100Y-1032433D01*
X270800Y-1031500D01*
X271000Y-1030567D01*
X271500Y-1029900D01*
X272200Y-1029500D01*
X272900D01*
X273600Y-1029767D01*
X274200Y-1030433D01*
G01X280500Y-1029500D02*
Y-1037500D01*
G01X278200Y-1029500D02*
X282800D01*
G01X287200Y-1034833D02*
X289800D01*
G01X296500Y-1029500D02*
Y-1037500D01*
G01X294200Y-1029500D02*
X298800D01*
G01X304500Y-1037500D02*
X303700Y-1037367D01*
X303000Y-1036833D01*
X302400Y-1036033D01*
X302000Y-1035100D01*
X301800Y-1034033D01*
Y-1032967D01*
X302000Y-1031900D01*
X302400Y-1030967D01*
X303000Y-1030167D01*
X303700Y-1029633D01*
X304500Y-1029500D01*
X305300Y-1029633D01*
X306000Y-1030167D01*
X306600Y-1030967D01*
X307000Y-1031900D01*
X307200Y-1032967D01*
Y-1034033D01*
X307000Y-1035100D01*
X306600Y-1036033D01*
X306000Y-1036833D01*
X305300Y-1037367D01*
X304500Y-1037500D01*
G01X310500D02*
Y-1029500D01*
X312900D01*
X313700Y-1029900D01*
X314300Y-1030833D01*
X314500Y-1031900D01*
X314300Y-1032967D01*
X313800Y-1033767D01*
X312900Y-1034167D01*
X310500D01*
G01X243000Y-1004500D02*
Y-1012500D01*
X247000D01*
G01X254800D02*
Y-1007167D01*
G01Y-1008100D02*
X254400Y-1007567D01*
X253800Y-1007300D01*
X253100Y-1007167D01*
X252400Y-1007433D01*
X251800Y-1007967D01*
X251400Y-1008767D01*
X251200Y-1009833D01*
X251400Y-1010900D01*
X251800Y-1011700D01*
X252400Y-1012233D01*
X253100Y-1012500D01*
X253800Y-1012367D01*
X254400Y-1011967D01*
X254800Y-1011434D01*
G01X258900Y-1014900D02*
X259500Y-1015167D01*
X260300Y-1014900D01*
X260800Y-1014367D01*
X261200Y-1013700D01*
X261800Y-1011567D01*
X263100Y-1007167D01*
G01X259900D02*
X261800Y-1011567D01*
G01X267500Y-1008900D02*
X270700D01*
X270400Y-1007967D01*
X269900Y-1007433D01*
X269200Y-1007167D01*
X268500Y-1007300D01*
X267900Y-1007700D01*
X267500Y-1008633D01*
X267300Y-1009434D01*
Y-1010233D01*
X267500Y-1011033D01*
X268000Y-1011833D01*
X268600Y-1012367D01*
X269300Y-1012500D01*
X270000Y-1012233D01*
X270700Y-1011434D01*
G01X275600Y-1012500D02*
Y-1007167D01*
G01Y-1008233D02*
X276100Y-1007700D01*
X276600Y-1007300D01*
X277300Y-1007167D01*
X277800Y-1007300D01*
X278400Y-1007700D01*
G01X262100Y-1054500D02*
X265900D01*
X262100Y-1062500D01*
X265900D01*
G01X272000Y-1057167D02*
Y-1062500D01*
G01Y-1055033D02*
X271800Y-1054900D01*
Y-1054633D01*
X272000Y-1054500D01*
X272200Y-1054633D01*
Y-1054900D01*
X272000Y-1055033D01*
G01X278700Y-1059833D02*
X281300D01*
G01X286200Y-1065167D02*
Y-1057167D01*
G01Y-1058367D02*
X286700Y-1057700D01*
X287200Y-1057300D01*
X288000Y-1057167D01*
X288700Y-1057300D01*
X289400Y-1057967D01*
X289700Y-1058900D01*
X289800Y-1059833D01*
X289700Y-1060767D01*
X289400Y-1061700D01*
X288800Y-1062233D01*
X288000Y-1062500D01*
X287300Y-1062367D01*
X286600Y-1061967D01*
X286200Y-1061434D01*
G01X296000Y-1057167D02*
Y-1062500D01*
G01Y-1055033D02*
X295800Y-1054900D01*
Y-1054633D01*
X296000Y-1054500D01*
X296200Y-1054633D01*
Y-1054900D01*
X296000Y-1055033D01*
G01X302300Y-1062500D02*
Y-1057167D01*
G01Y-1058500D02*
X302700Y-1057833D01*
X303300Y-1057300D01*
X304100Y-1057167D01*
X304800Y-1057300D01*
X305400Y-1057833D01*
X305700Y-1058767D01*
Y-1062500D01*
G01X310600Y-1064500D02*
X311300Y-1065033D01*
X312100Y-1065167D01*
X312800Y-1065033D01*
X313400Y-1064367D01*
X313800Y-1063433D01*
Y-1057167D01*
G01Y-1058233D02*
X313400Y-1057700D01*
X312800Y-1057300D01*
X312100Y-1057167D01*
X311300Y-1057433D01*
X310800Y-1057967D01*
X310400Y-1058900D01*
X310200Y-1059833D01*
X310300Y-1060633D01*
X310700Y-1061567D01*
X311300Y-1062233D01*
X312100Y-1062500D01*
X312700Y-1062367D01*
X313400Y-1061833D01*
X313800Y-1061300D01*
G01X369600Y-1055833D02*
X370200Y-1055033D01*
X370900Y-1054633D01*
X371700Y-1054500D01*
X372700Y-1054767D01*
X373400Y-1055433D01*
X373600Y-1056233D01*
X373500Y-1057034D01*
X373100Y-1057700D01*
X371100Y-1059033D01*
X370200Y-1059967D01*
X369600Y-1061300D01*
X369400Y-1062500D01*
X373600D01*
G01X379500Y-1054500D02*
X378700Y-1054767D01*
X378100Y-1055433D01*
X377700Y-1056233D01*
X377400Y-1057300D01*
X377300Y-1058500D01*
X377400Y-1059700D01*
X377700Y-1060767D01*
X378100Y-1061567D01*
X378700Y-1062233D01*
X379500Y-1062500D01*
X380300Y-1062233D01*
X380900Y-1061567D01*
X381300Y-1060767D01*
X381600Y-1059700D01*
X381700Y-1058500D01*
X381600Y-1057300D01*
X381300Y-1056233D01*
X380900Y-1055433D01*
X380300Y-1054767D01*
X379500Y-1054500D01*
G01X385600Y-1055833D02*
X386200Y-1055033D01*
X386900Y-1054633D01*
X387700Y-1054500D01*
X388700Y-1054767D01*
X389400Y-1055433D01*
X389600Y-1056233D01*
X389500Y-1057034D01*
X389100Y-1057700D01*
X387100Y-1059033D01*
X386200Y-1059967D01*
X385600Y-1061300D01*
X385400Y-1062500D01*
X389600D01*
G01X393600Y-1055833D02*
X394200Y-1055033D01*
X394900Y-1054633D01*
X395700Y-1054500D01*
X396700Y-1054767D01*
X397400Y-1055433D01*
X397600Y-1056233D01*
X397500Y-1057034D01*
X397100Y-1057700D01*
X395100Y-1059033D01*
X394200Y-1059967D01*
X393600Y-1061300D01*
X393400Y-1062500D01*
X397600D01*
G01X401700Y-1062767D02*
X405300Y-1054500D01*
G01X411500Y-1062500D02*
Y-1054500D01*
X410300Y-1056100D01*
G01Y-1062500D02*
X412700D01*
G01X417600Y-1055833D02*
X418200Y-1055033D01*
X418900Y-1054633D01*
X419700Y-1054500D01*
X420700Y-1054767D01*
X421400Y-1055433D01*
X421600Y-1056233D01*
X421500Y-1057034D01*
X421100Y-1057700D01*
X419100Y-1059033D01*
X418200Y-1059967D01*
X417600Y-1061300D01*
X417400Y-1062500D01*
X421600D01*
G01X425700Y-1062767D02*
X429300Y-1054500D01*
G01X435500Y-1062500D02*
Y-1054500D01*
X434300Y-1056100D01*
G01Y-1062500D02*
X436700D01*
G01X441300Y-1060900D02*
X441900Y-1061833D01*
X442700Y-1062367D01*
X443600Y-1062500D01*
X444400Y-1062367D01*
X445200Y-1061700D01*
X445700Y-1060900D01*
X445800Y-1060100D01*
X445600Y-1059167D01*
X444900Y-1058500D01*
X444200Y-1058233D01*
X443300D01*
G01X444200D02*
X444800Y-1057833D01*
X445300Y-1057167D01*
X445500Y-1056367D01*
X445300Y-1055567D01*
X444800Y-1054900D01*
X443900Y-1054500D01*
X443000Y-1054633D01*
X442100Y-1055167D01*
G01X369300Y-1040000D02*
Y-1032000D01*
X371300D01*
X372100Y-1032400D01*
X372700Y-1032933D01*
X373200Y-1033733D01*
X373600Y-1034667D01*
X373700Y-1036000D01*
X373600Y-1037333D01*
X373200Y-1038267D01*
X372700Y-1039067D01*
X372100Y-1039600D01*
X371300Y-1040000D01*
X369300D01*
G01X377000D02*
X379500Y-1032000D01*
X382000Y-1040000D01*
G01X381100Y-1037200D02*
X377900D01*
G01X385600Y-1040000D02*
Y-1032000D01*
X389400D01*
G01X388000Y-1035867D02*
X385600D01*
G01X395500Y-1032000D02*
X394700Y-1032267D01*
X394100Y-1032933D01*
X393700Y-1033733D01*
X393400Y-1034800D01*
X393300Y-1036000D01*
X393400Y-1037200D01*
X393700Y-1038267D01*
X394100Y-1039067D01*
X394700Y-1039733D01*
X395500Y-1040000D01*
X396300Y-1039733D01*
X396900Y-1039067D01*
X397300Y-1038267D01*
X397600Y-1037200D01*
X397700Y-1036000D01*
X397600Y-1034800D01*
X397300Y-1033733D01*
X396900Y-1032933D01*
X396300Y-1032267D01*
X395500Y-1032000D01*
G01X403500D02*
Y-1040000D01*
G01X401200Y-1032000D02*
X405800D01*
G01X409500Y-1040000D02*
Y-1032000D01*
X411900D01*
X412700Y-1032400D01*
X413300Y-1033333D01*
X413500Y-1034400D01*
X413300Y-1035467D01*
X412800Y-1036267D01*
X411900Y-1036667D01*
X409500D01*
G01X420300Y-1035733D02*
X420700Y-1035333D01*
X421000Y-1034667D01*
X421200Y-1033733D01*
X421000Y-1032933D01*
X420600Y-1032400D01*
X419900Y-1032000D01*
X417200D01*
Y-1040000D01*
X420500D01*
X421200Y-1039467D01*
X421600Y-1038667D01*
X421800Y-1037733D01*
X421600Y-1036800D01*
X421000Y-1036000D01*
X420300Y-1035733D01*
X417200D01*
G01X427500Y-1040000D02*
Y-1032000D01*
X426300Y-1033600D01*
G01Y-1040000D02*
X428700D01*
G01X433000D02*
X435500Y-1032000D01*
X438000Y-1040000D01*
G01X437100Y-1037200D02*
X433900D01*
G01X441600Y-1040000D02*
Y-1032000D01*
X445400D01*
G01X444000Y-1035867D02*
X441600D01*
G01X451500Y-1032000D02*
X450700Y-1032267D01*
X450100Y-1032933D01*
X449700Y-1033733D01*
X449400Y-1034800D01*
X449300Y-1036000D01*
X449400Y-1037200D01*
X449700Y-1038267D01*
X450100Y-1039067D01*
X450700Y-1039733D01*
X451500Y-1040000D01*
X452300Y-1039733D01*
X452900Y-1039067D01*
X453300Y-1038267D01*
X453600Y-1037200D01*
X453700Y-1036000D01*
X453600Y-1034800D01*
X453300Y-1033733D01*
X452900Y-1032933D01*
X452300Y-1032267D01*
X451500Y-1032000D01*
G01X389600Y-1012500D02*
Y-1004500D01*
X393400D01*
G01X392000Y-1008367D02*
X389600D01*
G01X399500Y-1004500D02*
X398700Y-1004767D01*
X398100Y-1005433D01*
X397700Y-1006233D01*
X397400Y-1007300D01*
X397300Y-1008500D01*
X397400Y-1009700D01*
X397700Y-1010767D01*
X398100Y-1011567D01*
X398700Y-1012233D01*
X399500Y-1012500D01*
X400300Y-1012233D01*
X400900Y-1011567D01*
X401300Y-1010767D01*
X401600Y-1009700D01*
X401700Y-1008500D01*
X401600Y-1007300D01*
X401300Y-1006233D01*
X400900Y-1005433D01*
X400300Y-1004767D01*
X399500Y-1004500D01*
G01X407500D02*
Y-1012500D01*
G01X405200Y-1004500D02*
X409800D01*
G01X412500Y-1015167D02*
X418500D01*
G01X421500Y-1012500D02*
Y-1004500D01*
X423900D01*
X424700Y-1004900D01*
X425300Y-1005833D01*
X425500Y-1006900D01*
X425300Y-1007967D01*
X424800Y-1008767D01*
X423900Y-1009167D01*
X421500D01*
G01X429300Y-1012500D02*
Y-1004500D01*
X431300D01*
X432100Y-1004900D01*
X432700Y-1005433D01*
X433200Y-1006233D01*
X433600Y-1007167D01*
X433700Y-1008500D01*
X433600Y-1009833D01*
X433200Y-1010767D01*
X432700Y-1011567D01*
X432100Y-1012100D01*
X431300Y-1012500D01*
X429300D01*
G01X440300Y-1008233D02*
X440700Y-1007833D01*
X441000Y-1007167D01*
X441200Y-1006233D01*
X441000Y-1005433D01*
X440600Y-1004900D01*
X439900Y-1004500D01*
X437200D01*
Y-1012500D01*
X440500D01*
X441200Y-1011967D01*
X441600Y-1011167D01*
X441800Y-1010233D01*
X441600Y-1009300D01*
X441000Y-1008500D01*
X440300Y-1008233D01*
X437200D01*
G01X444500Y-1015167D02*
X450500D01*
G01X456300Y-1008233D02*
X456700Y-1007833D01*
X457000Y-1007167D01*
X457200Y-1006233D01*
X457000Y-1005433D01*
X456600Y-1004900D01*
X455900Y-1004500D01*
X453200D01*
Y-1012500D01*
X456500D01*
X457200Y-1011967D01*
X457600Y-1011167D01*
X457800Y-1010233D01*
X457600Y-1009300D01*
X457000Y-1008500D01*
X456300Y-1008233D01*
X453200D01*
G01X461300Y-1012500D02*
Y-1004500D01*
X463300D01*
X464100Y-1004900D01*
X464700Y-1005433D01*
X465200Y-1006233D01*
X465600Y-1007167D01*
X465700Y-1008500D01*
X465600Y-1009833D01*
X465200Y-1010767D01*
X464700Y-1011567D01*
X464100Y-1012100D01*
X463300Y-1012500D01*
X461300D01*
G01X468500Y-1015167D02*
X474500D01*
G01X480100Y-1008500D02*
X482100D01*
Y-1010900D01*
X481500Y-1011700D01*
X480800Y-1012233D01*
X479800Y-1012500D01*
X478800Y-1012233D01*
X478100Y-1011700D01*
X477500Y-1010900D01*
X477100Y-1009967D01*
X476900Y-1008900D01*
Y-1007967D01*
X477100Y-1007167D01*
X477500Y-1006233D01*
X478100Y-1005433D01*
X478700Y-1004900D01*
X479500Y-1004500D01*
X480200D01*
X481000Y-1004767D01*
X481600Y-1005300D01*
G01X485500Y-1012500D02*
Y-1004500D01*
X487900D01*
X488700Y-1004900D01*
X489300Y-1005833D01*
X489500Y-1006900D01*
X489300Y-1007967D01*
X488800Y-1008767D01*
X487900Y-1009167D01*
X485500D01*
G01X493300Y-1004500D02*
Y-1010233D01*
X493700Y-1011434D01*
X494500Y-1012233D01*
X495500Y-1012500D01*
X496500Y-1012233D01*
X497300Y-1011434D01*
X497700Y-1010233D01*
Y-1004500D01*
G01X458000Y-1065500D02*
Y-1057500D01*
X456800Y-1059100D01*
G01Y-1065500D02*
X459200D01*
G01X464100Y-1062167D02*
X464800Y-1061233D01*
X465400Y-1060700D01*
X466200Y-1060433D01*
X466900Y-1060700D01*
X467400Y-1061233D01*
X467800Y-1062033D01*
X467900Y-1062967D01*
X467800Y-1063767D01*
X467400Y-1064567D01*
X466800Y-1065233D01*
X466100Y-1065500D01*
X465300Y-1065233D01*
X464600Y-1064434D01*
X464200Y-1063233D01*
X464100Y-1061900D01*
X464300Y-1060167D01*
X464600Y-1059233D01*
X465100Y-1058300D01*
X465800Y-1057633D01*
X466500Y-1057500D01*
X467200Y-1057767D01*
X467700Y-1058433D01*
G01X474000Y-1065767D02*
X473800Y-1065633D01*
Y-1065367D01*
X474000Y-1065233D01*
X474200Y-1065367D01*
Y-1065633D01*
X474000Y-1065767D01*
G01X480100Y-1062167D02*
X480800Y-1061233D01*
X481400Y-1060700D01*
X482200Y-1060433D01*
X482900Y-1060700D01*
X483400Y-1061233D01*
X483800Y-1062033D01*
X483900Y-1062967D01*
X483800Y-1063767D01*
X483400Y-1064567D01*
X482800Y-1065233D01*
X482100Y-1065500D01*
X481300Y-1065233D01*
X480600Y-1064434D01*
X480200Y-1063233D01*
X480100Y-1061900D01*
X480300Y-1060167D01*
X480600Y-1059233D01*
X481100Y-1058300D01*
X481800Y-1057633D01*
X482500Y-1057500D01*
X483200Y-1057767D01*
X483700Y-1058433D01*
G01X503000Y-1065500D02*
Y-1057500D01*
X501800Y-1059100D01*
G01Y-1065500D02*
X504200D01*
G01X510800D02*
X511000Y-1063767D01*
X511300Y-1062300D01*
X511700Y-1060967D01*
X512200Y-1059500D01*
X513000Y-1057500D01*
X509000D01*
G01X519000Y-1065767D02*
X518800Y-1065633D01*
Y-1065367D01*
X519000Y-1065233D01*
X519200Y-1065367D01*
Y-1065633D01*
X519000Y-1065767D01*
G01X525100Y-1058833D02*
X525700Y-1058033D01*
X526400Y-1057633D01*
X527200Y-1057500D01*
X528200Y-1057767D01*
X528900Y-1058433D01*
X529100Y-1059233D01*
X529000Y-1060034D01*
X528600Y-1060700D01*
X526600Y-1062033D01*
X525700Y-1062967D01*
X525100Y-1064300D01*
X524900Y-1065500D01*
X529100D01*
G01X523100Y-1040500D02*
Y-1032500D01*
X526900D01*
G01X525500Y-1036367D02*
X523100D01*
G54D65*
X1759880Y267724D03*
Y312016D03*
G54D38*
X631000Y313760D03*
Y321240D03*
G54D56*
X1651774Y118613D03*
G36*
G01X1275733Y57333D02*
X1269827D01*
Y64026D01*
X1272530D01*
Y64813D01*
X1269827D01*
Y71506D01*
X1272530D01*
Y72294D01*
X1269827D01*
Y78987D01*
X1272530D01*
Y79774D01*
X1269827D01*
Y82870D01*
X1263528D01*
Y79774D01*
X1260825D01*
Y78987D01*
X1263528D01*
Y72294D01*
X1260825D01*
Y71506D01*
X1263528D01*
Y64813D01*
X1260825D01*
Y64026D01*
X1263528D01*
Y57333D01*
X1257623D01*
Y64026D01*
X1260325D01*
Y64813D01*
X1257623D01*
Y71506D01*
X1260325D01*
Y72294D01*
X1257623D01*
Y78987D01*
X1260325D01*
Y79774D01*
X1257623D01*
Y82870D01*
X1251323D01*
Y79577D01*
X1247341D01*
Y78396D01*
X1251323D01*
Y72491D01*
X1247341D01*
Y71309D01*
X1251323D01*
Y65404D01*
X1247341D01*
Y64223D01*
X1251323D01*
Y58317D01*
X1247341D01*
Y57136D01*
X1251323D01*
Y51231D01*
X1242859D01*
Y57136D01*
X1246841D01*
Y58317D01*
X1242859D01*
Y64223D01*
X1246841D01*
Y65404D01*
X1242859D01*
Y71309D01*
X1246841D01*
Y72491D01*
X1242859D01*
Y78396D01*
X1246841D01*
Y79577D01*
X1242859D01*
Y85483D01*
X1246841D01*
Y86664D01*
X1242859D01*
Y92569D01*
X1251323D01*
Y86664D01*
X1247341D01*
Y85483D01*
X1251323D01*
Y83370D01*
X1257623D01*
Y86467D01*
X1263528D01*
Y83370D01*
X1269827D01*
Y86467D01*
X1275733D01*
Y79774D01*
X1273030D01*
Y78987D01*
X1275733D01*
Y72294D01*
X1273030D01*
Y71506D01*
X1275733D01*
Y64813D01*
X1273030D01*
Y64026D01*
X1275733D01*
Y57333D01*
G37*
G36*
G01Y101733D02*
X1269827D01*
Y108426D01*
X1272530D01*
Y109213D01*
X1269827D01*
Y115906D01*
X1272530D01*
Y116694D01*
X1269827D01*
Y123387D01*
X1272530D01*
Y124174D01*
X1269827D01*
Y127270D01*
X1263528D01*
Y124174D01*
X1260825D01*
Y123387D01*
X1263528D01*
Y116694D01*
X1260825D01*
Y115906D01*
X1263528D01*
Y109213D01*
X1260825D01*
Y108426D01*
X1263528D01*
Y101733D01*
X1257623D01*
Y108426D01*
X1260325D01*
Y109213D01*
X1257623D01*
Y115906D01*
X1260325D01*
Y116694D01*
X1257623D01*
Y123387D01*
X1260325D01*
Y124174D01*
X1257623D01*
Y127270D01*
X1251323D01*
Y123977D01*
X1247341D01*
Y122796D01*
X1251323D01*
Y116891D01*
X1247341D01*
Y115709D01*
X1251323D01*
Y109804D01*
X1247341D01*
Y108623D01*
X1251323D01*
Y102717D01*
X1247341D01*
Y101536D01*
X1251323D01*
Y95631D01*
X1242859D01*
Y101536D01*
X1246841D01*
Y102717D01*
X1242859D01*
Y108623D01*
X1246841D01*
Y109804D01*
X1242859D01*
Y115709D01*
X1246841D01*
Y116891D01*
X1242859D01*
Y122796D01*
X1246841D01*
Y123977D01*
X1242859D01*
Y129883D01*
X1246841D01*
Y131064D01*
X1242859D01*
Y136969D01*
X1251323D01*
Y131064D01*
X1247341D01*
Y129883D01*
X1251323D01*
Y127770D01*
X1257623D01*
Y130867D01*
X1263528D01*
Y127770D01*
X1269827D01*
Y130867D01*
X1275733D01*
Y124174D01*
X1273030D01*
Y123387D01*
X1275733D01*
Y116694D01*
X1273030D01*
Y115906D01*
X1275733D01*
Y109213D01*
X1273030D01*
Y108426D01*
X1275733D01*
Y101733D01*
G37*
G36*
G01Y146133D02*
X1269827D01*
Y152826D01*
X1272530D01*
Y153613D01*
X1269827D01*
Y160306D01*
X1272530D01*
Y161094D01*
X1269827D01*
Y167787D01*
X1272530D01*
Y168574D01*
X1269827D01*
Y171670D01*
X1263528D01*
Y168574D01*
X1260825D01*
Y167787D01*
X1263528D01*
Y161094D01*
X1260825D01*
Y160306D01*
X1263528D01*
Y153613D01*
X1260825D01*
Y152826D01*
X1263528D01*
Y146133D01*
X1257623D01*
Y152826D01*
X1260325D01*
Y153613D01*
X1257623D01*
Y160306D01*
X1260325D01*
Y161094D01*
X1257623D01*
Y167787D01*
X1260325D01*
Y168574D01*
X1257623D01*
Y171670D01*
X1251323D01*
Y168377D01*
X1247341D01*
Y167196D01*
X1251323D01*
Y161291D01*
X1247341D01*
Y160109D01*
X1251323D01*
Y154204D01*
X1247341D01*
Y153023D01*
X1251323D01*
Y147117D01*
X1247341D01*
Y145936D01*
X1251323D01*
Y140031D01*
X1242859D01*
Y145936D01*
X1246841D01*
Y147117D01*
X1242859D01*
Y153023D01*
X1246841D01*
Y154204D01*
X1242859D01*
Y160109D01*
X1246841D01*
Y161291D01*
X1242859D01*
Y167196D01*
X1246841D01*
Y168377D01*
X1242859D01*
Y174283D01*
X1246841D01*
Y175464D01*
X1242859D01*
Y181369D01*
X1251323D01*
Y175464D01*
X1247341D01*
Y174283D01*
X1251323D01*
Y172170D01*
X1257623D01*
Y175267D01*
X1263528D01*
Y172170D01*
X1269827D01*
Y175267D01*
X1275733D01*
Y168574D01*
X1273030D01*
Y167787D01*
X1275733D01*
Y161094D01*
X1273030D01*
Y160306D01*
X1275733D01*
Y153613D01*
X1273030D01*
Y152826D01*
X1275733D01*
Y146133D01*
G37*
G36*
G01Y190533D02*
X1269827D01*
Y197226D01*
X1272530D01*
Y198013D01*
X1269827D01*
Y204706D01*
X1272530D01*
Y205494D01*
X1269827D01*
Y212187D01*
X1272530D01*
Y212974D01*
X1269827D01*
Y216070D01*
X1263528D01*
Y212974D01*
X1260825D01*
Y212187D01*
X1263528D01*
Y205494D01*
X1260825D01*
Y204706D01*
X1263528D01*
Y198013D01*
X1260825D01*
Y197226D01*
X1263528D01*
Y190533D01*
X1257623D01*
Y197226D01*
X1260325D01*
Y198013D01*
X1257623D01*
Y204706D01*
X1260325D01*
Y205494D01*
X1257623D01*
Y212187D01*
X1260325D01*
Y212974D01*
X1257623D01*
Y216070D01*
X1251323D01*
Y212777D01*
X1247341D01*
Y211596D01*
X1251323D01*
Y205691D01*
X1247341D01*
Y204509D01*
X1251323D01*
Y198604D01*
X1247341D01*
Y197423D01*
X1251323D01*
Y191517D01*
X1247341D01*
Y190336D01*
X1251323D01*
Y184431D01*
X1242859D01*
Y190336D01*
X1246841D01*
Y191517D01*
X1242859D01*
Y197423D01*
X1246841D01*
Y198604D01*
X1242859D01*
Y204509D01*
X1246841D01*
Y205691D01*
X1242859D01*
Y211596D01*
X1246841D01*
Y212777D01*
X1242859D01*
Y218683D01*
X1246841D01*
Y219864D01*
X1242859D01*
Y225769D01*
X1251323D01*
Y219864D01*
X1247341D01*
Y218683D01*
X1251323D01*
Y216570D01*
X1257623D01*
Y219667D01*
X1263528D01*
Y216570D01*
X1269827D01*
Y219667D01*
X1275733D01*
Y212974D01*
X1273030D01*
Y212187D01*
X1275733D01*
Y205494D01*
X1273030D01*
Y204706D01*
X1275733D01*
Y198013D01*
X1273030D01*
Y197226D01*
X1275733D01*
Y190533D01*
G37*
G36*
G01Y234933D02*
X1269827D01*
Y241626D01*
X1272530D01*
Y242413D01*
X1269827D01*
Y249106D01*
X1272530D01*
Y249894D01*
X1269827D01*
Y256587D01*
X1272530D01*
Y257374D01*
X1269827D01*
Y260470D01*
X1263528D01*
Y257374D01*
X1260825D01*
Y256587D01*
X1263528D01*
Y249894D01*
X1260825D01*
Y249106D01*
X1263528D01*
Y242413D01*
X1260825D01*
Y241626D01*
X1263528D01*
Y234933D01*
X1257623D01*
Y241626D01*
X1260325D01*
Y242413D01*
X1257623D01*
Y249106D01*
X1260325D01*
Y249894D01*
X1257623D01*
Y256587D01*
X1260325D01*
Y257374D01*
X1257623D01*
Y260470D01*
X1251323D01*
Y257177D01*
X1247341D01*
Y255996D01*
X1251323D01*
Y250091D01*
X1247341D01*
Y248909D01*
X1251323D01*
Y243004D01*
X1247341D01*
Y241823D01*
X1251323D01*
Y235917D01*
X1247341D01*
Y234736D01*
X1251323D01*
Y228831D01*
X1242859D01*
Y234736D01*
X1246841D01*
Y235917D01*
X1242859D01*
Y241823D01*
X1246841D01*
Y243004D01*
X1242859D01*
Y248909D01*
X1246841D01*
Y250091D01*
X1242859D01*
Y255996D01*
X1246841D01*
Y257177D01*
X1242859D01*
Y263083D01*
X1246841D01*
Y264264D01*
X1242859D01*
Y270169D01*
X1251323D01*
Y264264D01*
X1247341D01*
Y263083D01*
X1251323D01*
Y260970D01*
X1257623D01*
Y264067D01*
X1263528D01*
Y260970D01*
X1269827D01*
Y264067D01*
X1275733D01*
Y257374D01*
X1273030D01*
Y256587D01*
X1275733D01*
Y249894D01*
X1273030D01*
Y249106D01*
X1275733D01*
Y242413D01*
X1273030D01*
Y241626D01*
X1275733D01*
Y234933D01*
G37*
G36*
G01Y279333D02*
X1269827D01*
Y286026D01*
X1272530D01*
Y286813D01*
X1269827D01*
Y293506D01*
X1272530D01*
Y294294D01*
X1269827D01*
Y300987D01*
X1272530D01*
Y301774D01*
X1269827D01*
Y304870D01*
X1263528D01*
Y301774D01*
X1260825D01*
Y300987D01*
X1263528D01*
Y294294D01*
X1260825D01*
Y293506D01*
X1263528D01*
Y286813D01*
X1260825D01*
Y286026D01*
X1263528D01*
Y279333D01*
X1257623D01*
Y286026D01*
X1260325D01*
Y286813D01*
X1257623D01*
Y293506D01*
X1260325D01*
Y294294D01*
X1257623D01*
Y300987D01*
X1260325D01*
Y301774D01*
X1257623D01*
Y304870D01*
X1251323D01*
Y301577D01*
X1247341D01*
Y300396D01*
X1251323D01*
Y294491D01*
X1247341D01*
Y293309D01*
X1251323D01*
Y287404D01*
X1247341D01*
Y286223D01*
X1251323D01*
Y280317D01*
X1247341D01*
Y279136D01*
X1251323D01*
Y273231D01*
X1242859D01*
Y279136D01*
X1246841D01*
Y280317D01*
X1242859D01*
Y286223D01*
X1246841D01*
Y287404D01*
X1242859D01*
Y293309D01*
X1246841D01*
Y294491D01*
X1242859D01*
Y300396D01*
X1246841D01*
Y301577D01*
X1242859D01*
Y307483D01*
X1246841D01*
Y308664D01*
X1242859D01*
Y314569D01*
X1251323D01*
Y308664D01*
X1247341D01*
Y307483D01*
X1251323D01*
Y305370D01*
X1257623D01*
Y308467D01*
X1263528D01*
Y305370D01*
X1269827D01*
Y308467D01*
X1275733D01*
Y301774D01*
X1273030D01*
Y300987D01*
X1275733D01*
Y294294D01*
X1273030D01*
Y293506D01*
X1275733D01*
Y286813D01*
X1273030D01*
Y286026D01*
X1275733D01*
Y279333D01*
G37*
G54D29*
X462338Y61900D03*
Y81900D03*
Y106300D03*
Y126300D03*
Y150700D03*
Y170700D03*
Y195100D03*
Y215100D03*
Y239500D03*
Y259500D03*
Y283900D03*
Y303900D03*
G54D48*
X1299946Y81900D03*
Y61900D03*
Y106300D03*
Y126300D03*
Y170700D03*
Y150700D03*
Y195100D03*
Y215100D03*
Y239500D03*
Y259500D03*
Y283900D03*
Y303900D03*
G54D57*
X1673000Y114646D03*
Y95354D03*
G54D39*
X643941Y324740D03*
X649059D03*
Y317260D03*
X646500D03*
X643941D03*
X725559Y305260D03*
X720441D03*
Y312740D03*
X723000D03*
X725559D03*
G54D66*
X1751706Y328965D03*
X1762730Y342351D03*
G54D49*
X1625426Y79800D03*
X1641174D03*
G54D67*
X1756037Y330540D03*
X1758399D03*
Y340776D03*
G54D58*
X1706100Y86500D03*
X1701100D03*
X1696100D03*
X1691100D03*
Y107300D03*
X1696100D03*
X1701100D03*
X1706100D03*
G54D59*
X1732100Y104500D03*
Y109500D03*
Y114500D03*
Y119500D03*
Y124500D03*
Y129500D03*
Y134500D03*
X1752900Y114500D03*
Y109500D03*
Y104500D03*
Y134500D03*
Y129500D03*
Y124500D03*
Y119500D03*
G54D68*
X1762533Y328965D03*
G54D69*
X1751389Y357827D03*
X1758389D03*
X1751389Y350127D03*
X1758389D03*
X1765600Y370000D03*
Y363000D03*
X1751389Y365527D03*
X1758389D03*
X1751389Y373227D03*
X1758389D03*
X1772600Y370000D03*
Y363000D03*
M02*
